FILE_TYPE = MACRO_DRAWING;
SET COLOR_WIRE YELLOW;
SET COLOR_PROP ORANGE;
SET COLOR_DOT WHITE;
SET COLOR_ARC YELLOW;
SET COLOR_BODY GREEN;
SET COLOR_NOTE PURPLE;
SET PROP_DISPLAY VALUE;
SET PAGE_NUMBER P57;
FORCEADD VCC_CORE..1
(-7425 6600);
FORCEPROP 3 LASTPIN (-7425 6550) SIG_NAME PVDDCR_CPU0_P1\g
J 0
(-7415 6560);
DISPLAY 0.659574 (-7415 6560);
PAINT MONO (-7415 6560);
DISPLAY INVISIBLE (-7415 6560);
FORCEPROP 1 LAST HDL_POWER PVDDCR_CPU0_P1
J 1
(-7425 6650);
DISPLAY 0.489362 (-7425 6650);
PAINT GREEN (-7425 6650);
FORCEPROP 2 LAST CDS_LIB pure_quanta_power
J 0
(-7425 6600);
DISPLAY INVISIBLE (-7425 6600);
FORCEPROP 1 LAST PATH I27
J 0
(-7375 6625);
DISPLAY 0.872340 (-7375 6625);
PAINT AQUA (-7375 6625);
DISPLAY INVISIBLE (-7375 6625);
FORCEADD VCC_CORE..1
(-8875 6600);
FORCEPROP 3 LASTPIN (-8875 6550) SIG_NAME PVDDCR_CPU0_P1\g
J 0
(-8865 6560);
DISPLAY 0.659574 (-8865 6560);
PAINT MONO (-8865 6560);
DISPLAY INVISIBLE (-8865 6560);
FORCEPROP 1 LAST HDL_POWER PVDDCR_CPU0_P1
J 1
(-8875 6650);
DISPLAY 0.489362 (-8875 6650);
PAINT GREEN (-8875 6650);
FORCEPROP 2 LAST CDS_LIB pure_quanta_power
J 0
(-8875 6600);
DISPLAY INVISIBLE (-8875 6600);
FORCEPROP 1 LAST PATH I28
J 0
(-8825 6625);
DISPLAY 0.872340 (-8825 6625);
PAINT AQUA (-8825 6625);
DISPLAY INVISIBLE (-8825 6625);
FORCEADD GENOA_SP5..24
(-8150 3350);
FORCEPROP 1 LAST LOCATION U26
J 0
(-8650 6600);
DISPLAY 0.489362 (-8650 6600);
PAINT SKYBLUE (-8650 6600);
FORCEPROP 0 LAST $SEC 24
J 0
(-8625 6850);
DISPLAY 0.680851 (-8625 6850);
PAINT MONO (-8625 6850);
DISPLAY INVISIBLE (-8625 6850);
FORCEPROP 0 LAST CDS_SEC 24
J 0
(-8625 6850);
DISPLAY 1.021277 (-8625 6850);
DISPLAY INVISIBLE (-8625 6850);
FORCEPROP 0 LASTPIN (-7500 5950) $PN AB23
J 0
(-7490 5960);
DISPLAY 0.489362 (-7490 5960);
PAINT MONO (-7490 5960);
FORCEPROP 0 LASTPIN (-7500 5900) $PN AB24
J 0
(-7490 5910);
DISPLAY 0.489362 (-7490 5910);
PAINT MONO (-7490 5910);
FORCEPROP 0 LASTPIN (-7500 5850) $PN AB26
J 0
(-7490 5860);
DISPLAY 0.489362 (-7490 5860);
PAINT MONO (-7490 5860);
FORCEPROP 0 LASTPIN (-7500 5800) $PN AB27
J 0
(-7490 5810);
DISPLAY 0.489362 (-7490 5810);
PAINT MONO (-7490 5810);
FORCEPROP 0 LASTPIN (-7500 5750) $PN AB29
J 0
(-7490 5760);
DISPLAY 0.489362 (-7490 5760);
PAINT MONO (-7490 5760);
FORCEPROP 0 LASTPIN (-7500 5700) $PN AB30
J 0
(-7490 5710);
DISPLAY 0.489362 (-7490 5710);
PAINT MONO (-7490 5710);
FORCEPROP 0 LASTPIN (-7500 5650) $PN AB32
J 0
(-7490 5660);
DISPLAY 0.489362 (-7490 5660);
PAINT MONO (-7490 5660);
FORCEPROP 0 LASTPIN (-7500 5600) $PN AB33
J 0
(-7490 5610);
DISPLAY 0.489362 (-7490 5610);
PAINT MONO (-7490 5610);
FORCEPROP 0 LASTPIN (-7500 5550) $PN AB43
J 0
(-7490 5560);
DISPLAY 0.489362 (-7490 5560);
PAINT MONO (-7490 5560);
FORCEPROP 0 LASTPIN (-7500 5500) $PN AB44
J 0
(-7490 5510);
DISPLAY 0.489362 (-7490 5510);
PAINT MONO (-7490 5510);
FORCEPROP 0 LASTPIN (-7500 5450) $PN AB46
J 0
(-7490 5460);
DISPLAY 0.489362 (-7490 5460);
PAINT MONO (-7490 5460);
FORCEPROP 0 LASTPIN (-7500 5400) $PN AB47
J 0
(-7490 5410);
DISPLAY 0.489362 (-7490 5410);
PAINT MONO (-7490 5410);
FORCEPROP 0 LASTPIN (-7500 5350) $PN AB49
J 0
(-7490 5360);
DISPLAY 0.489362 (-7490 5360);
PAINT MONO (-7490 5360);
FORCEPROP 0 LASTPIN (-7500 5300) $PN AB50
J 0
(-7490 5310);
DISPLAY 0.489362 (-7490 5310);
PAINT MONO (-7490 5310);
FORCEPROP 0 LASTPIN (-7500 5250) $PN AB52
J 0
(-7490 5260);
DISPLAY 0.489362 (-7490 5260);
PAINT MONO (-7490 5260);
FORCEPROP 0 LASTPIN (-7500 5200) $PN AB53
J 0
(-7490 5210);
DISPLAY 0.489362 (-7490 5210);
PAINT MONO (-7490 5210);
FORCEPROP 0 LASTPIN (-7500 5150) $PN AC35
J 0
(-7490 5160);
DISPLAY 0.489362 (-7490 5160);
PAINT MONO (-7490 5160);
FORCEPROP 0 LASTPIN (-7500 5100) $PN AC36
J 0
(-7490 5110);
DISPLAY 0.489362 (-7490 5110);
PAINT MONO (-7490 5110);
FORCEPROP 0 LASTPIN (-7500 5050) $PN AC40
J 0
(-7490 5060);
DISPLAY 0.489362 (-7490 5060);
PAINT MONO (-7490 5060);
FORCEPROP 0 LASTPIN (-7500 5000) $PN AC41
J 0
(-7490 5010);
DISPLAY 0.489362 (-7490 5010);
PAINT MONO (-7490 5010);
FORCEPROP 0 LASTPIN (-7500 4950) $PN AF23
J 0
(-7490 4960);
DISPLAY 0.489362 (-7490 4960);
PAINT MONO (-7490 4960);
FORCEPROP 0 LASTPIN (-7500 4900) $PN AF24
J 0
(-7490 4910);
DISPLAY 0.489362 (-7490 4910);
PAINT MONO (-7490 4910);
FORCEPROP 0 LASTPIN (-7500 4850) $PN AF26
J 0
(-7490 4860);
DISPLAY 0.489362 (-7490 4860);
PAINT MONO (-7490 4860);
FORCEPROP 0 LASTPIN (-7500 4800) $PN AF27
J 0
(-7490 4810);
DISPLAY 0.489362 (-7490 4810);
PAINT MONO (-7490 4810);
FORCEPROP 0 LASTPIN (-7500 4750) $PN AF29
J 0
(-7490 4760);
DISPLAY 0.489362 (-7490 4760);
PAINT MONO (-7490 4760);
FORCEPROP 0 LASTPIN (-7500 4700) $PN AF30
J 0
(-7490 4710);
DISPLAY 0.489362 (-7490 4710);
PAINT MONO (-7490 4710);
FORCEPROP 0 LASTPIN (-7500 4650) $PN AF32
J 0
(-7490 4660);
DISPLAY 0.489362 (-7490 4660);
PAINT MONO (-7490 4660);
FORCEPROP 0 LASTPIN (-7500 4600) $PN AF33
J 0
(-7490 4610);
DISPLAY 0.489362 (-7490 4610);
PAINT MONO (-7490 4610);
FORCEPROP 0 LASTPIN (-7500 4550) $PN AF43
J 0
(-7490 4560);
DISPLAY 0.489362 (-7490 4560);
PAINT MONO (-7490 4560);
FORCEPROP 0 LASTPIN (-7500 4500) $PN AF44
J 0
(-7490 4510);
DISPLAY 0.489362 (-7490 4510);
PAINT MONO (-7490 4510);
FORCEPROP 0 LASTPIN (-7500 4450) $PN AF46
J 0
(-7490 4460);
DISPLAY 0.489362 (-7490 4460);
PAINT MONO (-7490 4460);
FORCEPROP 0 LASTPIN (-7500 4400) $PN AF47
J 0
(-7490 4410);
DISPLAY 0.489362 (-7490 4410);
PAINT MONO (-7490 4410);
FORCEPROP 0 LASTPIN (-7500 4350) $PN AF49
J 0
(-7490 4360);
DISPLAY 0.489362 (-7490 4360);
PAINT MONO (-7490 4360);
FORCEPROP 0 LASTPIN (-7500 4300) $PN AF50
J 0
(-7490 4310);
DISPLAY 0.489362 (-7490 4310);
PAINT MONO (-7490 4310);
FORCEPROP 0 LASTPIN (-7500 4250) $PN AF52
J 0
(-7490 4260);
DISPLAY 0.489362 (-7490 4260);
PAINT MONO (-7490 4260);
FORCEPROP 0 LASTPIN (-7500 4200) $PN AF53
J 0
(-7490 4210);
DISPLAY 0.489362 (-7490 4210);
PAINT MONO (-7490 4210);
FORCEPROP 0 LASTPIN (-7500 4150) $PN AG35
J 0
(-7490 4160);
DISPLAY 0.489362 (-7490 4160);
PAINT MONO (-7490 4160);
FORCEPROP 0 LASTPIN (-7500 4100) $PN AG36
J 0
(-7490 4110);
DISPLAY 0.489362 (-7490 4110);
PAINT MONO (-7490 4110);
FORCEPROP 0 LASTPIN (-7500 4050) $PN AG40
J 0
(-7490 4060);
DISPLAY 0.489362 (-7490 4060);
PAINT MONO (-7490 4060);
FORCEPROP 0 LASTPIN (-7500 4000) $PN AG41
J 0
(-7490 4010);
DISPLAY 0.489362 (-7490 4010);
PAINT MONO (-7490 4010);
FORCEPROP 0 LASTPIN (-7500 3950) $PN AK23
J 0
(-7490 3960);
DISPLAY 0.489362 (-7490 3960);
PAINT MONO (-7490 3960);
FORCEPROP 0 LASTPIN (-7500 3900) $PN AK24
J 0
(-7490 3910);
DISPLAY 0.489362 (-7490 3910);
PAINT MONO (-7490 3910);
FORCEPROP 0 LASTPIN (-7500 3850) $PN AK26
J 0
(-7490 3860);
DISPLAY 0.489362 (-7490 3860);
PAINT MONO (-7490 3860);
FORCEPROP 0 LASTPIN (-7500 3800) $PN AK27
J 0
(-7490 3810);
DISPLAY 0.489362 (-7490 3810);
PAINT MONO (-7490 3810);
FORCEPROP 0 LASTPIN (-7500 3750) $PN AK29
J 0
(-7490 3760);
DISPLAY 0.489362 (-7490 3760);
PAINT MONO (-7490 3760);
FORCEPROP 0 LASTPIN (-7500 3700) $PN AK30
J 0
(-7490 3710);
DISPLAY 0.489362 (-7490 3710);
PAINT MONO (-7490 3710);
FORCEPROP 0 LASTPIN (-7500 3650) $PN AK32
J 0
(-7490 3660);
DISPLAY 0.489362 (-7490 3660);
PAINT MONO (-7490 3660);
FORCEPROP 0 LASTPIN (-7500 3600) $PN AK33
J 0
(-7490 3610);
DISPLAY 0.489362 (-7490 3610);
PAINT MONO (-7490 3610);
FORCEPROP 0 LASTPIN (-7500 3550) $PN AK43
J 0
(-7490 3560);
DISPLAY 0.489362 (-7490 3560);
PAINT MONO (-7490 3560);
FORCEPROP 0 LASTPIN (-7500 3500) $PN AK44
J 0
(-7490 3510);
DISPLAY 0.489362 (-7490 3510);
PAINT MONO (-7490 3510);
FORCEPROP 0 LASTPIN (-7500 3450) $PN AK46
J 0
(-7490 3460);
DISPLAY 0.489362 (-7490 3460);
PAINT MONO (-7490 3460);
FORCEPROP 0 LASTPIN (-7500 3400) $PN AK47
J 0
(-7490 3410);
DISPLAY 0.489362 (-7490 3410);
PAINT MONO (-7490 3410);
FORCEPROP 0 LASTPIN (-7500 3350) $PN AK49
J 0
(-7490 3360);
DISPLAY 0.489362 (-7490 3360);
PAINT MONO (-7490 3360);
FORCEPROP 0 LASTPIN (-7500 3300) $PN AK50
J 0
(-7490 3310);
DISPLAY 0.489362 (-7490 3310);
PAINT MONO (-7490 3310);
FORCEPROP 0 LASTPIN (-7500 3250) $PN AK52
J 0
(-7490 3260);
DISPLAY 0.489362 (-7490 3260);
PAINT MONO (-7490 3260);
FORCEPROP 0 LASTPIN (-7500 3200) $PN AK53
J 0
(-7490 3210);
DISPLAY 0.489362 (-7490 3210);
PAINT MONO (-7490 3210);
FORCEPROP 0 LASTPIN (-7500 3150) $PN AL35
J 0
(-7490 3160);
DISPLAY 0.489362 (-7490 3160);
PAINT MONO (-7490 3160);
FORCEPROP 0 LASTPIN (-7500 3100) $PN AL36
J 0
(-7490 3110);
DISPLAY 0.489362 (-7490 3110);
PAINT MONO (-7490 3110);
FORCEPROP 0 LASTPIN (-7500 3050) $PN AL40
J 0
(-7490 3060);
DISPLAY 0.489362 (-7490 3060);
PAINT MONO (-7490 3060);
FORCEPROP 0 LASTPIN (-7500 3000) $PN AL41
J 0
(-7490 3010);
DISPLAY 0.489362 (-7490 3010);
PAINT MONO (-7490 3010);
FORCEPROP 0 LASTPIN (-7500 2950) $PN AP23
J 0
(-7490 2960);
DISPLAY 0.489362 (-7490 2960);
PAINT MONO (-7490 2960);
FORCEPROP 0 LASTPIN (-7500 2900) $PN AP24
J 0
(-7490 2910);
DISPLAY 0.489362 (-7490 2910);
PAINT MONO (-7490 2910);
FORCEPROP 0 LASTPIN (-7500 2850) $PN AP26
J 0
(-7490 2860);
DISPLAY 0.489362 (-7490 2860);
PAINT MONO (-7490 2860);
FORCEPROP 0 LASTPIN (-7500 2800) $PN AP27
J 0
(-7490 2810);
DISPLAY 0.489362 (-7490 2810);
PAINT MONO (-7490 2810);
FORCEPROP 0 LASTPIN (-7500 2750) $PN AP29
J 0
(-7490 2760);
DISPLAY 0.489362 (-7490 2760);
PAINT MONO (-7490 2760);
FORCEPROP 0 LASTPIN (-7500 2700) $PN AP30
J 0
(-7490 2710);
DISPLAY 0.489362 (-7490 2710);
PAINT MONO (-7490 2710);
FORCEPROP 0 LASTPIN (-7500 2650) $PN AP32
J 0
(-7490 2660);
DISPLAY 0.489362 (-7490 2660);
PAINT MONO (-7490 2660);
FORCEPROP 0 LASTPIN (-7500 2600) $PN AP33
J 0
(-7490 2610);
DISPLAY 0.489362 (-7490 2610);
PAINT MONO (-7490 2610);
FORCEPROP 0 LASTPIN (-7500 2550) $PN AP43
J 0
(-7490 2560);
DISPLAY 0.489362 (-7490 2560);
PAINT MONO (-7490 2560);
FORCEPROP 0 LASTPIN (-7500 2500) $PN AP44
J 0
(-7490 2510);
DISPLAY 0.489362 (-7490 2510);
PAINT MONO (-7490 2510);
FORCEPROP 0 LASTPIN (-7500 2450) $PN AP46
J 0
(-7490 2460);
DISPLAY 0.489362 (-7490 2460);
PAINT MONO (-7490 2460);
FORCEPROP 0 LASTPIN (-7500 2400) $PN AP47
J 0
(-7490 2410);
DISPLAY 0.489362 (-7490 2410);
PAINT MONO (-7490 2410);
FORCEPROP 0 LASTPIN (-7500 2350) $PN AP49
J 0
(-7490 2360);
DISPLAY 0.489362 (-7490 2360);
PAINT MONO (-7490 2360);
FORCEPROP 0 LASTPIN (-7500 2300) $PN AP50
J 0
(-7490 2310);
DISPLAY 0.489362 (-7490 2310);
PAINT MONO (-7490 2310);
FORCEPROP 0 LASTPIN (-7500 2250) $PN AP52
J 0
(-7490 2260);
DISPLAY 0.489362 (-7490 2260);
PAINT MONO (-7490 2260);
FORCEPROP 0 LASTPIN (-7500 2200) $PN AP53
J 0
(-7490 2210);
DISPLAY 0.489362 (-7490 2210);
PAINT MONO (-7490 2210);
FORCEPROP 0 LASTPIN (-7500 2150) $PN AR23
J 0
(-7490 2160);
DISPLAY 0.489362 (-7490 2160);
PAINT MONO (-7490 2160);
FORCEPROP 0 LASTPIN (-7500 2100) $PN AR25
J 0
(-7490 2110);
DISPLAY 0.489362 (-7490 2110);
PAINT MONO (-7490 2110);
FORCEPROP 0 LASTPIN (-7500 2050) $PN AR27
J 0
(-7490 2060);
DISPLAY 0.489362 (-7490 2060);
PAINT MONO (-7490 2060);
FORCEPROP 0 LASTPIN (-7500 2000) $PN AR29
J 0
(-7490 2010);
DISPLAY 0.489362 (-7490 2010);
PAINT MONO (-7490 2010);
FORCEPROP 0 LASTPIN (-7500 1950) $PN AR31
J 0
(-7490 1960);
DISPLAY 0.489362 (-7490 1960);
PAINT MONO (-7490 1960);
FORCEPROP 0 LASTPIN (-7500 1900) $PN AR33
J 0
(-7490 1910);
DISPLAY 0.489362 (-7490 1910);
PAINT MONO (-7490 1910);
FORCEPROP 0 LASTPIN (-7500 1850) $PN AR35
J 0
(-7490 1860);
DISPLAY 0.489362 (-7490 1860);
PAINT MONO (-7490 1860);
FORCEPROP 0 LASTPIN (-7500 1800) $PN AR40
J 0
(-7490 1810);
DISPLAY 0.489362 (-7490 1810);
PAINT MONO (-7490 1810);
FORCEPROP 0 LASTPIN (-7500 1750) $PN AR42
J 0
(-7490 1760);
DISPLAY 0.489362 (-7490 1760);
PAINT MONO (-7490 1760);
FORCEPROP 0 LASTPIN (-7500 1700) $PN AR44
J 0
(-7490 1710);
DISPLAY 0.489362 (-7490 1710);
PAINT MONO (-7490 1710);
FORCEPROP 0 LASTPIN (-7500 1650) $PN AR46
J 0
(-7490 1660);
DISPLAY 0.489362 (-7490 1660);
PAINT MONO (-7490 1660);
FORCEPROP 0 LASTPIN (-7500 1600) $PN AR48
J 0
(-7490 1610);
DISPLAY 0.489362 (-7490 1610);
PAINT MONO (-7490 1610);
FORCEPROP 0 LASTPIN (-7500 1550) $PN AR50
J 0
(-7490 1560);
DISPLAY 0.489362 (-7490 1560);
PAINT MONO (-7490 1560);
FORCEPROP 0 LASTPIN (-7500 1500) $PN AT24
J 0
(-7490 1510);
DISPLAY 0.489362 (-7490 1510);
PAINT MONO (-7490 1510);
FORCEPROP 0 LASTPIN (-7500 1450) $PN AT26
J 0
(-7490 1460);
DISPLAY 0.489362 (-7490 1460);
PAINT MONO (-7490 1460);
FORCEPROP 0 LASTPIN (-7500 1400) $PN AT28
J 0
(-7490 1410);
DISPLAY 0.489362 (-7490 1410);
PAINT MONO (-7490 1410);
FORCEPROP 0 LASTPIN (-7500 1350) $PN AT30
J 0
(-7490 1360);
DISPLAY 0.489362 (-7490 1360);
PAINT MONO (-7490 1360);
FORCEPROP 0 LASTPIN (-7500 1300) $PN AT32
J 0
(-7490 1310);
DISPLAY 0.489362 (-7490 1310);
PAINT MONO (-7490 1310);
FORCEPROP 0 LASTPIN (-7500 1250) $PN AT34
J 0
(-7490 1260);
DISPLAY 0.489362 (-7490 1260);
PAINT MONO (-7490 1260);
FORCEPROP 0 LASTPIN (-7500 1200) $PN AT36
J 0
(-7490 1210);
DISPLAY 0.489362 (-7490 1210);
PAINT MONO (-7490 1210);
FORCEPROP 0 LASTPIN (-7500 1150) $PN AT39
J 0
(-7490 1160);
DISPLAY 0.489362 (-7490 1160);
PAINT MONO (-7490 1160);
FORCEPROP 0 LASTPIN (-7500 1100) $PN AT41
J 0
(-7490 1110);
DISPLAY 0.489362 (-7490 1110);
PAINT MONO (-7490 1110);
FORCEPROP 0 LASTPIN (-7500 1050) $PN AT43
J 0
(-7490 1060);
DISPLAY 0.489362 (-7490 1060);
PAINT MONO (-7490 1060);
FORCEPROP 0 LASTPIN (-7500 1000) $PN AT45
J 0
(-7490 1010);
DISPLAY 0.489362 (-7490 1010);
PAINT MONO (-7490 1010);
FORCEPROP 0 LASTPIN (-7500 950) $PN AT47
J 0
(-7490 960);
DISPLAY 0.489362 (-7490 960);
PAINT MONO (-7490 960);
FORCEPROP 0 LASTPIN (-7500 900) $PN AT49
J 0
(-7490 910);
DISPLAY 0.489362 (-7490 910);
PAINT MONO (-7490 910);
FORCEPROP 0 LASTPIN (-7500 600) $PN AU25
J 0
(-7490 610);
DISPLAY 0.489362 (-7490 610);
PAINT MONO (-7490 610);
FORCEPROP 0 LASTPIN (-7500 850) $PN AU29
J 0
(-7490 860);
DISPLAY 0.489362 (-7490 860);
PAINT MONO (-7490 860);
FORCEPROP 0 LASTPIN (-7500 550) $PN AU33
J 0
(-7490 560);
DISPLAY 0.489362 (-7490 560);
PAINT MONO (-7490 560);
FORCEPROP 0 LASTPIN (-7500 800) $PN AU42
J 0
(-7490 810);
DISPLAY 0.489362 (-7490 810);
PAINT MONO (-7490 810);
FORCEPROP 0 LASTPIN (-7500 700) $PN AU44
J 0
(-7490 710);
DISPLAY 0.489362 (-7490 710);
PAINT MONO (-7490 710);
FORCEPROP 0 LASTPIN (-7500 750) $PN AU46
J 0
(-7490 760);
DISPLAY 0.489362 (-7490 760);
PAINT MONO (-7490 760);
FORCEPROP 0 LASTPIN (-7500 650) $PN AU48
J 0
(-7490 660);
DISPLAY 0.489362 (-7490 660);
PAINT MONO (-7490 660);
FORCEPROP 0 LASTPIN (-8800 6350) $PN B19
J 2
(-8810 6360);
DISPLAY 0.489362 (-8810 6360);
PAINT MONO (-8810 6360);
FORCEPROP 0 LASTPIN (-8800 6300) $PN B20
J 2
(-8810 6310);
DISPLAY 0.489362 (-8810 6310);
PAINT MONO (-8810 6310);
FORCEPROP 0 LASTPIN (-8800 6250) $PN B22
J 2
(-8810 6260);
DISPLAY 0.489362 (-8810 6260);
PAINT MONO (-8810 6260);
FORCEPROP 0 LASTPIN (-8800 6200) $PN B23
J 2
(-8810 6210);
DISPLAY 0.489362 (-8810 6210);
PAINT MONO (-8810 6210);
FORCEPROP 0 LASTPIN (-8800 6150) $PN B25
J 2
(-8810 6160);
DISPLAY 0.489362 (-8810 6160);
PAINT MONO (-8810 6160);
FORCEPROP 0 LASTPIN (-8800 6100) $PN B26
J 2
(-8810 6110);
DISPLAY 0.489362 (-8810 6110);
PAINT MONO (-8810 6110);
FORCEPROP 0 LASTPIN (-8800 6050) $PN B28
J 2
(-8810 6060);
DISPLAY 0.489362 (-8810 6060);
PAINT MONO (-8810 6060);
FORCEPROP 0 LASTPIN (-8800 6000) $PN B29
J 2
(-8810 6010);
DISPLAY 0.489362 (-8810 6010);
PAINT MONO (-8810 6010);
FORCEPROP 0 LASTPIN (-8800 5950) $PN B31
J 2
(-8810 5960);
DISPLAY 0.489362 (-8810 5960);
PAINT MONO (-8810 5960);
FORCEPROP 0 LASTPIN (-8800 5900) $PN B32
J 2
(-8810 5910);
DISPLAY 0.489362 (-8810 5910);
PAINT MONO (-8810 5910);
FORCEPROP 0 LASTPIN (-8800 5850) $PN B34
J 2
(-8810 5860);
DISPLAY 0.489362 (-8810 5860);
PAINT MONO (-8810 5860);
FORCEPROP 0 LASTPIN (-8800 5800) $PN B35
J 2
(-8810 5810);
DISPLAY 0.489362 (-8810 5810);
PAINT MONO (-8810 5810);
FORCEPROP 0 LASTPIN (-8800 5750) $PN B41
J 2
(-8810 5760);
DISPLAY 0.489362 (-8810 5760);
PAINT MONO (-8810 5760);
FORCEPROP 0 LASTPIN (-8800 5700) $PN B42
J 2
(-8810 5710);
DISPLAY 0.489362 (-8810 5710);
PAINT MONO (-8810 5710);
FORCEPROP 0 LASTPIN (-8800 5650) $PN B44
J 2
(-8810 5660);
DISPLAY 0.489362 (-8810 5660);
PAINT MONO (-8810 5660);
FORCEPROP 0 LASTPIN (-8800 5600) $PN B45
J 2
(-8810 5610);
DISPLAY 0.489362 (-8810 5610);
PAINT MONO (-8810 5610);
FORCEPROP 0 LASTPIN (-8800 5550) $PN B47
J 2
(-8810 5560);
DISPLAY 0.489362 (-8810 5560);
PAINT MONO (-8810 5560);
FORCEPROP 0 LASTPIN (-8800 5500) $PN B48
J 2
(-8810 5510);
DISPLAY 0.489362 (-8810 5510);
PAINT MONO (-8810 5510);
FORCEPROP 0 LASTPIN (-8800 5450) $PN B50
J 2
(-8810 5460);
DISPLAY 0.489362 (-8810 5460);
PAINT MONO (-8810 5460);
FORCEPROP 0 LASTPIN (-8800 5400) $PN B51
J 2
(-8810 5410);
DISPLAY 0.489362 (-8810 5410);
PAINT MONO (-8810 5410);
FORCEPROP 0 LASTPIN (-8800 5350) $PN B53
J 2
(-8810 5360);
DISPLAY 0.489362 (-8810 5360);
PAINT MONO (-8810 5360);
FORCEPROP 0 LASTPIN (-8800 5300) $PN B54
J 2
(-8810 5310);
DISPLAY 0.489362 (-8810 5310);
PAINT MONO (-8810 5310);
FORCEPROP 0 LASTPIN (-8800 5250) $PN B56
J 2
(-8810 5260);
DISPLAY 0.489362 (-8810 5260);
PAINT MONO (-8810 5260);
FORCEPROP 0 LASTPIN (-8800 5200) $PN B57
J 2
(-8810 5210);
DISPLAY 0.489362 (-8810 5210);
PAINT MONO (-8810 5210);
FORCEPROP 0 LASTPIN (-8800 5150) $PN C20
J 2
(-8810 5160);
DISPLAY 0.489362 (-8810 5160);
PAINT MONO (-8810 5160);
FORCEPROP 0 LASTPIN (-8800 5100) $PN D55
J 2
(-8810 5110);
DISPLAY 0.489362 (-8810 5110);
PAINT MONO (-8810 5110);
FORCEPROP 0 LASTPIN (-8800 5050) $PN D56
J 2
(-8810 5060);
DISPLAY 0.489362 (-8810 5060);
PAINT MONO (-8810 5060);
FORCEPROP 0 LASTPIN (-8800 5000) $PN E22
J 2
(-8810 5010);
DISPLAY 0.489362 (-8810 5010);
PAINT MONO (-8810 5010);
FORCEPROP 0 LASTPIN (-8800 4950) $PN E25
J 2
(-8810 4960);
DISPLAY 0.489362 (-8810 4960);
PAINT MONO (-8810 4960);
FORCEPROP 0 LASTPIN (-8800 4900) $PN E28
J 2
(-8810 4910);
DISPLAY 0.489362 (-8810 4910);
PAINT MONO (-8810 4910);
FORCEPROP 0 LASTPIN (-8800 4850) $PN E31
J 2
(-8810 4860);
DISPLAY 0.489362 (-8810 4860);
PAINT MONO (-8810 4860);
FORCEPROP 0 LASTPIN (-8800 4800) $PN E34
J 2
(-8810 4810);
DISPLAY 0.489362 (-8810 4810);
PAINT MONO (-8810 4810);
FORCEPROP 0 LASTPIN (-8800 4750) $PN E35
J 2
(-8810 4760);
DISPLAY 0.489362 (-8810 4760);
PAINT MONO (-8810 4760);
FORCEPROP 0 LASTPIN (-8800 4700) $PN E42
J 2
(-8810 4710);
DISPLAY 0.489362 (-8810 4710);
PAINT MONO (-8810 4710);
FORCEPROP 0 LASTPIN (-8800 4650) $PN E45
J 2
(-8810 4660);
DISPLAY 0.489362 (-8810 4660);
PAINT MONO (-8810 4660);
FORCEPROP 0 LASTPIN (-8800 4600) $PN E48
J 2
(-8810 4610);
DISPLAY 0.489362 (-8810 4610);
PAINT MONO (-8810 4610);
FORCEPROP 0 LASTPIN (-8800 4550) $PN E51
J 2
(-8810 4560);
DISPLAY 0.489362 (-8810 4560);
PAINT MONO (-8810 4560);
FORCEPROP 0 LASTPIN (-8800 4500) $PN E54
J 2
(-8810 4510);
DISPLAY 0.489362 (-8810 4510);
PAINT MONO (-8810 4510);
FORCEPROP 0 LASTPIN (-8800 4450) $PN F22
J 2
(-8810 4460);
DISPLAY 0.489362 (-8810 4460);
PAINT MONO (-8810 4460);
FORCEPROP 0 LASTPIN (-8800 4400) $PN F25
J 2
(-8810 4410);
DISPLAY 0.489362 (-8810 4410);
PAINT MONO (-8810 4410);
FORCEPROP 0 LASTPIN (-8800 4350) $PN F28
J 2
(-8810 4360);
DISPLAY 0.489362 (-8810 4360);
PAINT MONO (-8810 4360);
FORCEPROP 0 LASTPIN (-8800 4300) $PN F31
J 2
(-8810 4310);
DISPLAY 0.489362 (-8810 4310);
PAINT MONO (-8810 4310);
FORCEPROP 0 LASTPIN (-8800 4250) $PN F34
J 2
(-8810 4260);
DISPLAY 0.489362 (-8810 4260);
PAINT MONO (-8810 4260);
FORCEPROP 0 LASTPIN (-8800 4200) $PN F42
J 2
(-8810 4210);
DISPLAY 0.489362 (-8810 4210);
PAINT MONO (-8810 4210);
FORCEPROP 0 LASTPIN (-8800 4150) $PN F45
J 2
(-8810 4160);
DISPLAY 0.489362 (-8810 4160);
PAINT MONO (-8810 4160);
FORCEPROP 0 LASTPIN (-8800 4100) $PN F48
J 2
(-8810 4110);
DISPLAY 0.489362 (-8810 4110);
PAINT MONO (-8810 4110);
FORCEPROP 0 LASTPIN (-8800 4050) $PN F51
J 2
(-8810 4060);
DISPLAY 0.489362 (-8810 4060);
PAINT MONO (-8810 4060);
FORCEPROP 0 LASTPIN (-8800 4000) $PN F54
J 2
(-8810 4010);
DISPLAY 0.489362 (-8810 4010);
PAINT MONO (-8810 4010);
FORCEPROP 0 LASTPIN (-8800 3950) $PN G35
J 2
(-8810 3960);
DISPLAY 0.489362 (-8810 3960);
PAINT MONO (-8810 3960);
FORCEPROP 0 LASTPIN (-8800 3900) $PN G36
J 2
(-8810 3910);
DISPLAY 0.489362 (-8810 3910);
PAINT MONO (-8810 3910);
FORCEPROP 0 LASTPIN (-8800 3850) $PN G40
J 2
(-8810 3860);
DISPLAY 0.489362 (-8810 3860);
PAINT MONO (-8810 3860);
FORCEPROP 0 LASTPIN (-8800 3800) $PN G41
J 2
(-8810 3810);
DISPLAY 0.489362 (-8810 3810);
PAINT MONO (-8810 3810);
FORCEPROP 0 LASTPIN (-8800 3750) $PN H23
J 2
(-8810 3760);
DISPLAY 0.489362 (-8810 3760);
PAINT MONO (-8810 3760);
FORCEPROP 0 LASTPIN (-8800 3700) $PN H24
J 2
(-8810 3710);
DISPLAY 0.489362 (-8810 3710);
PAINT MONO (-8810 3710);
FORCEPROP 0 LASTPIN (-8800 3650) $PN H26
J 2
(-8810 3660);
DISPLAY 0.489362 (-8810 3660);
PAINT MONO (-8810 3660);
FORCEPROP 0 LASTPIN (-8800 3600) $PN H27
J 2
(-8810 3610);
DISPLAY 0.489362 (-8810 3610);
PAINT MONO (-8810 3610);
FORCEPROP 0 LASTPIN (-8800 3550) $PN H29
J 2
(-8810 3560);
DISPLAY 0.489362 (-8810 3560);
PAINT MONO (-8810 3560);
FORCEPROP 0 LASTPIN (-8800 3500) $PN H30
J 2
(-8810 3510);
DISPLAY 0.489362 (-8810 3510);
PAINT MONO (-8810 3510);
FORCEPROP 0 LASTPIN (-8800 3450) $PN H32
J 2
(-8810 3460);
DISPLAY 0.489362 (-8810 3460);
PAINT MONO (-8810 3460);
FORCEPROP 0 LASTPIN (-8800 3400) $PN H33
J 2
(-8810 3410);
DISPLAY 0.489362 (-8810 3410);
PAINT MONO (-8810 3410);
FORCEPROP 0 LASTPIN (-8800 3350) $PN H43
J 2
(-8810 3360);
DISPLAY 0.489362 (-8810 3360);
PAINT MONO (-8810 3360);
FORCEPROP 0 LASTPIN (-8800 3300) $PN H44
J 2
(-8810 3310);
DISPLAY 0.489362 (-8810 3310);
PAINT MONO (-8810 3310);
FORCEPROP 0 LASTPIN (-8800 3250) $PN H46
J 2
(-8810 3260);
DISPLAY 0.489362 (-8810 3260);
PAINT MONO (-8810 3260);
FORCEPROP 0 LASTPIN (-8800 3200) $PN H47
J 2
(-8810 3210);
DISPLAY 0.489362 (-8810 3210);
PAINT MONO (-8810 3210);
FORCEPROP 0 LASTPIN (-8800 3150) $PN H49
J 2
(-8810 3160);
DISPLAY 0.489362 (-8810 3160);
PAINT MONO (-8810 3160);
FORCEPROP 0 LASTPIN (-8800 3100) $PN H50
J 2
(-8810 3110);
DISPLAY 0.489362 (-8810 3110);
PAINT MONO (-8810 3110);
FORCEPROP 0 LASTPIN (-8800 3050) $PN H52
J 2
(-8810 3060);
DISPLAY 0.489362 (-8810 3060);
PAINT MONO (-8810 3060);
FORCEPROP 0 LASTPIN (-8800 3000) $PN H53
J 2
(-8810 3010);
DISPLAY 0.489362 (-8810 3010);
PAINT MONO (-8810 3010);
FORCEPROP 0 LASTPIN (-8800 2950) $PN J35
J 2
(-8810 2960);
DISPLAY 0.489362 (-8810 2960);
PAINT MONO (-8810 2960);
FORCEPROP 0 LASTPIN (-8800 2900) $PN J36
J 2
(-8810 2910);
DISPLAY 0.489362 (-8810 2910);
PAINT MONO (-8810 2910);
FORCEPROP 0 LASTPIN (-8800 2850) $PN J40
J 2
(-8810 2860);
DISPLAY 0.489362 (-8810 2860);
PAINT MONO (-8810 2860);
FORCEPROP 0 LASTPIN (-8800 2800) $PN J41
J 2
(-8810 2810);
DISPLAY 0.489362 (-8810 2810);
PAINT MONO (-8810 2810);
FORCEPROP 0 LASTPIN (-8800 2750) $PN M23
J 2
(-8810 2760);
DISPLAY 0.489362 (-8810 2760);
PAINT MONO (-8810 2760);
FORCEPROP 0 LASTPIN (-8800 2700) $PN M24
J 2
(-8810 2710);
DISPLAY 0.489362 (-8810 2710);
PAINT MONO (-8810 2710);
FORCEPROP 0 LASTPIN (-8800 2650) $PN M26
J 2
(-8810 2660);
DISPLAY 0.489362 (-8810 2660);
PAINT MONO (-8810 2660);
FORCEPROP 0 LASTPIN (-8800 2600) $PN M27
J 2
(-8810 2610);
DISPLAY 0.489362 (-8810 2610);
PAINT MONO (-8810 2610);
FORCEPROP 0 LASTPIN (-8800 2550) $PN M29
J 2
(-8810 2560);
DISPLAY 0.489362 (-8810 2560);
PAINT MONO (-8810 2560);
FORCEPROP 0 LASTPIN (-8800 2500) $PN M30
J 2
(-8810 2510);
DISPLAY 0.489362 (-8810 2510);
PAINT MONO (-8810 2510);
FORCEPROP 0 LASTPIN (-8800 2450) $PN M32
J 2
(-8810 2460);
DISPLAY 0.489362 (-8810 2460);
PAINT MONO (-8810 2460);
FORCEPROP 0 LASTPIN (-8800 2400) $PN M33
J 2
(-8810 2410);
DISPLAY 0.489362 (-8810 2410);
PAINT MONO (-8810 2410);
FORCEPROP 0 LASTPIN (-8800 2350) $PN M43
J 2
(-8810 2360);
DISPLAY 0.489362 (-8810 2360);
PAINT MONO (-8810 2360);
FORCEPROP 0 LASTPIN (-8800 2300) $PN M44
J 2
(-8810 2310);
DISPLAY 0.489362 (-8810 2310);
PAINT MONO (-8810 2310);
FORCEPROP 0 LASTPIN (-8800 2250) $PN M46
J 2
(-8810 2260);
DISPLAY 0.489362 (-8810 2260);
PAINT MONO (-8810 2260);
FORCEPROP 0 LASTPIN (-8800 2200) $PN M47
J 2
(-8810 2210);
DISPLAY 0.489362 (-8810 2210);
PAINT MONO (-8810 2210);
FORCEPROP 0 LASTPIN (-8800 2150) $PN M49
J 2
(-8810 2160);
DISPLAY 0.489362 (-8810 2160);
PAINT MONO (-8810 2160);
FORCEPROP 0 LASTPIN (-8800 2100) $PN M50
J 2
(-8810 2110);
DISPLAY 0.489362 (-8810 2110);
PAINT MONO (-8810 2110);
FORCEPROP 0 LASTPIN (-8800 2050) $PN M52
J 2
(-8810 2060);
DISPLAY 0.489362 (-8810 2060);
PAINT MONO (-8810 2060);
FORCEPROP 0 LASTPIN (-8800 2000) $PN M53
J 2
(-8810 2010);
DISPLAY 0.489362 (-8810 2010);
PAINT MONO (-8810 2010);
FORCEPROP 0 LASTPIN (-8800 1950) $PN N35
J 2
(-8810 1960);
DISPLAY 0.489362 (-8810 1960);
PAINT MONO (-8810 1960);
FORCEPROP 0 LASTPIN (-8800 1900) $PN N36
J 2
(-8810 1910);
DISPLAY 0.489362 (-8810 1910);
PAINT MONO (-8810 1910);
FORCEPROP 0 LASTPIN (-8800 1850) $PN N40
J 2
(-8810 1860);
DISPLAY 0.489362 (-8810 1860);
PAINT MONO (-8810 1860);
FORCEPROP 0 LASTPIN (-8800 1800) $PN N41
J 2
(-8810 1810);
DISPLAY 0.489362 (-8810 1810);
PAINT MONO (-8810 1810);
FORCEPROP 0 LASTPIN (-8800 1750) $PN T23
J 2
(-8810 1760);
DISPLAY 0.489362 (-8810 1760);
PAINT MONO (-8810 1760);
FORCEPROP 0 LASTPIN (-8800 1700) $PN T24
J 2
(-8810 1710);
DISPLAY 0.489362 (-8810 1710);
PAINT MONO (-8810 1710);
FORCEPROP 0 LASTPIN (-8800 1650) $PN T26
J 2
(-8810 1660);
DISPLAY 0.489362 (-8810 1660);
PAINT MONO (-8810 1660);
FORCEPROP 0 LASTPIN (-8800 1600) $PN T27
J 2
(-8810 1610);
DISPLAY 0.489362 (-8810 1610);
PAINT MONO (-8810 1610);
FORCEPROP 0 LASTPIN (-8800 1550) $PN T29
J 2
(-8810 1560);
DISPLAY 0.489362 (-8810 1560);
PAINT MONO (-8810 1560);
FORCEPROP 0 LASTPIN (-8800 1500) $PN T30
J 2
(-8810 1510);
DISPLAY 0.489362 (-8810 1510);
PAINT MONO (-8810 1510);
FORCEPROP 0 LASTPIN (-8800 1450) $PN T32
J 2
(-8810 1460);
DISPLAY 0.489362 (-8810 1460);
PAINT MONO (-8810 1460);
FORCEPROP 0 LASTPIN (-8800 1400) $PN T33
J 2
(-8810 1410);
DISPLAY 0.489362 (-8810 1410);
PAINT MONO (-8810 1410);
FORCEPROP 0 LASTPIN (-8800 1350) $PN T43
J 2
(-8810 1360);
DISPLAY 0.489362 (-8810 1360);
PAINT MONO (-8810 1360);
FORCEPROP 0 LASTPIN (-8800 1300) $PN T44
J 2
(-8810 1310);
DISPLAY 0.489362 (-8810 1310);
PAINT MONO (-8810 1310);
FORCEPROP 0 LASTPIN (-8800 1250) $PN T46
J 2
(-8810 1260);
DISPLAY 0.489362 (-8810 1260);
PAINT MONO (-8810 1260);
FORCEPROP 0 LASTPIN (-8800 1200) $PN T47
J 2
(-8810 1210);
DISPLAY 0.489362 (-8810 1210);
PAINT MONO (-8810 1210);
FORCEPROP 0 LASTPIN (-8800 1150) $PN T49
J 2
(-8810 1160);
DISPLAY 0.489362 (-8810 1160);
PAINT MONO (-8810 1160);
FORCEPROP 0 LASTPIN (-8800 1100) $PN T50
J 2
(-8810 1110);
DISPLAY 0.489362 (-8810 1110);
PAINT MONO (-8810 1110);
FORCEPROP 0 LASTPIN (-8800 1050) $PN T52
J 2
(-8810 1060);
DISPLAY 0.489362 (-8810 1060);
PAINT MONO (-8810 1060);
FORCEPROP 0 LASTPIN (-8800 1000) $PN T53
J 2
(-8810 1010);
DISPLAY 0.489362 (-8810 1010);
PAINT MONO (-8810 1010);
FORCEPROP 0 LASTPIN (-8800 950) $PN U35
J 2
(-8810 960);
DISPLAY 0.489362 (-8810 960);
PAINT MONO (-8810 960);
FORCEPROP 0 LASTPIN (-8800 900) $PN U36
J 2
(-8810 910);
DISPLAY 0.489362 (-8810 910);
PAINT MONO (-8810 910);
FORCEPROP 0 LASTPIN (-8800 850) $PN U40
J 2
(-8810 860);
DISPLAY 0.489362 (-8810 860);
PAINT MONO (-8810 860);
FORCEPROP 0 LASTPIN (-8800 800) $PN U41
J 2
(-8810 810);
DISPLAY 0.489362 (-8810 810);
PAINT MONO (-8810 810);
FORCEPROP 0 LASTPIN (-8800 750) $PN W29
J 2
(-8810 760);
DISPLAY 0.489362 (-8810 760);
PAINT MONO (-8810 760);
FORCEPROP 0 LASTPIN (-8800 700) $PN W30
J 2
(-8810 710);
DISPLAY 0.489362 (-8810 710);
PAINT MONO (-8810 710);
FORCEPROP 0 LASTPIN (-8800 650) $PN W32
J 2
(-8810 660);
DISPLAY 0.489362 (-8810 660);
PAINT MONO (-8810 660);
FORCEPROP 0 LASTPIN (-8800 600) $PN W33
J 2
(-8810 610);
DISPLAY 0.489362 (-8810 610);
PAINT MONO (-8810 610);
FORCEPROP 0 LASTPIN (-7500 6350) $PN W43
J 0
(-7490 6360);
DISPLAY 0.489362 (-7490 6360);
PAINT MONO (-7490 6360);
FORCEPROP 0 LASTPIN (-7500 6300) $PN W44
J 0
(-7490 6310);
DISPLAY 0.489362 (-7490 6310);
PAINT MONO (-7490 6310);
FORCEPROP 0 LASTPIN (-7500 6250) $PN W46
J 0
(-7490 6260);
DISPLAY 0.489362 (-7490 6260);
PAINT MONO (-7490 6260);
FORCEPROP 0 LASTPIN (-7500 6200) $PN W47
J 0
(-7490 6210);
DISPLAY 0.489362 (-7490 6210);
PAINT MONO (-7490 6210);
FORCEPROP 0 LASTPIN (-7500 6150) $PN Y35
J 0
(-7490 6160);
DISPLAY 0.489362 (-7490 6160);
PAINT MONO (-7490 6160);
FORCEPROP 0 LASTPIN (-7500 6100) $PN Y36
J 0
(-7490 6110);
DISPLAY 0.489362 (-7490 6110);
PAINT MONO (-7490 6110);
FORCEPROP 0 LASTPIN (-7500 6050) $PN Y40
J 0
(-7490 6060);
DISPLAY 0.489362 (-7490 6060);
PAINT MONO (-7490 6060);
FORCEPROP 0 LASTPIN (-7500 6000) $PN Y41
J 0
(-7490 6010);
DISPLAY 0.489362 (-7490 6010);
PAINT MONO (-7490 6010);
FORCEPROP 1 LAST MATERIAL IO
J 0
(-8645 6520);
DISPLAY 0.489362 (-8645 6520);
PAINT SKYBLUE (-8645 6520);
FORCEPROP 2 LAST PART_TYPE SMLF
J 0
(-8650 6675);
DISPLAY 1.021277 (-8650 6675);
FORCEPROP 1 LAST PART_NUMBER DGA^6000030
J 0
(-8645 6647);
DISPLAY 0.489362 (-8645 6647);
PAINT SKYBLUE (-8645 6647);
FORCEPROP 2 LAST VALUE SOCKET6096_13568-001
J 0
(-8650 6575);
DISPLAY 0.489362 (-8650 6575);
PAINT SKYBLUE (-8650 6575);
FORCEPROP 2 LAST CDS_LIB pure_quanta
J 0
(-8150 3350);
DISPLAY INVISIBLE (-8150 3350);
FORCEPROP 1 LAST CDS_LMAN_SYM_OUTLINE -500,3150,500,-3150
J 0
(-8150 3350);
DISPLAY 0.468085 (-8150 3350);
PAINT GREEN (-8150 3350);
DISPLAY INVISIBLE (-8150 3350);
FORCEPROP 1 LAST NEEDS_NO_SIZE TRUE
J 0
(-8150 3350);
DISPLAY 0.723404 (-8150 3350);
PAINT GREEN (-8150 3350);
DISPLAY INVISIBLE (-8150 3350);
FORCEPROP 1 LAST PATH I29
J 0
(-8150 3350);
DISPLAY 0.723404 (-8150 3350);
PAINT GREEN (-8150 3350);
DISPLAY INVISIBLE (-8150 3350);
FORCEADD VCC_CORE..1
(-5525 6550);
FORCEPROP 3 LASTPIN (-5525 6500) SIG_NAME PVDDCR_CPU1_P1\g
J 0
(-5515 6510);
DISPLAY 0.659574 (-5515 6510);
PAINT MONO (-5515 6510);
DISPLAY INVISIBLE (-5515 6510);
FORCEPROP 1 LAST HDL_POWER PVDDCR_CPU1_P1
J 1
(-5525 6600);
DISPLAY 0.489362 (-5525 6600);
PAINT GREEN (-5525 6600);
FORCEPROP 2 LAST CDS_LIB pure_quanta_power
J 0
(-5525 6550);
DISPLAY INVISIBLE (-5525 6550);
FORCEPROP 1 LAST PATH I30
J 0
(-5475 6575);
DISPLAY 0.872340 (-5475 6575);
PAINT AQUA (-5475 6575);
DISPLAY INVISIBLE (-5475 6575);
FORCEADD VCC_CORE..1
(-6950 6325);
FORCEPROP 3 LASTPIN (-6950 6275) SIG_NAME PVDDCR_CPU1_P1\g
J 0
(-6940 6285);
DISPLAY 0.659574 (-6940 6285);
PAINT MONO (-6940 6285);
DISPLAY INVISIBLE (-6940 6285);
FORCEPROP 1 LAST HDL_POWER PVDDCR_CPU1_P1
J 1
(-6950 6375);
DISPLAY 0.489362 (-6950 6375);
PAINT GREEN (-6950 6375);
FORCEPROP 2 LAST CDS_LIB pure_quanta_power
J 0
(-6950 6325);
DISPLAY INVISIBLE (-6950 6325);
FORCEPROP 1 LAST PATH I31
J 0
(-6900 6350);
DISPLAY 0.872340 (-6900 6350);
PAINT AQUA (-6900 6350);
DISPLAY INVISIBLE (-6900 6350);
FORCEADD GENOA_SP5..25
(-6225 3375);
FORCEPROP 1 LAST LOCATION U26
J 0
(-6725 6675);
DISPLAY 0.489362 (-6725 6675);
PAINT SKYBLUE (-6725 6675);
FORCEPROP 0 LAST $SEC 25
J 0
(-6700 6925);
DISPLAY 0.680851 (-6700 6925);
PAINT MONO (-6700 6925);
DISPLAY INVISIBLE (-6700 6925);
FORCEPROP 0 LAST CDS_SEC 25
J 0
(-6700 6925);
DISPLAY 1.021277 (-6700 6925);
DISPLAY INVISIBLE (-6700 6925);
FORCEPROP 0 LASTPIN (-5575 525) $PN BN27
J 0
(-5565 535);
DISPLAY 0.489362 (-5565 535);
PAINT MONO (-5565 535);
FORCEPROP 0 LASTPIN (-6875 6125) $PN BN31
J 2
(-6885 6135);
DISPLAY 0.489362 (-6885 6135);
PAINT MONO (-6885 6135);
FORCEPROP 0 LASTPIN (-5575 475) $PN BN35
J 0
(-5565 485);
DISPLAY 0.489362 (-5565 485);
PAINT MONO (-5565 485);
FORCEPROP 0 LASTPIN (-6875 6075) $PN BN42
J 2
(-6885 6085);
DISPLAY 0.489362 (-6885 6085);
PAINT MONO (-6885 6085);
FORCEPROP 0 LASTPIN (-5575 425) $PN BN46
J 0
(-5565 435);
DISPLAY 0.489362 (-5565 435);
PAINT MONO (-5565 435);
FORCEPROP 0 LASTPIN (-6875 6025) $PN BN50
J 2
(-6885 6035);
DISPLAY 0.489362 (-6885 6035);
PAINT MONO (-6885 6035);
FORCEPROP 0 LASTPIN (-5575 375) $PN BP24
J 0
(-5565 385);
DISPLAY 0.489362 (-5565 385);
PAINT MONO (-5565 385);
FORCEPROP 0 LASTPIN (-6875 5975) $PN BP26
J 2
(-6885 5985);
DISPLAY 0.489362 (-6885 5985);
PAINT MONO (-6885 5985);
FORCEPROP 0 LASTPIN (-5575 325) $PN BP28
J 0
(-5565 335);
DISPLAY 0.489362 (-5565 335);
PAINT MONO (-5565 335);
FORCEPROP 0 LASTPIN (-6875 5925) $PN BP30
J 2
(-6885 5935);
DISPLAY 0.489362 (-6885 5935);
PAINT MONO (-6885 5935);
FORCEPROP 0 LASTPIN (-5575 275) $PN BP32
J 0
(-5565 285);
DISPLAY 0.489362 (-5565 285);
PAINT MONO (-5565 285);
FORCEPROP 0 LASTPIN (-6875 5875) $PN BP34
J 2
(-6885 5885);
DISPLAY 0.489362 (-6885 5885);
PAINT MONO (-6885 5885);
FORCEPROP 0 LASTPIN (-6875 5825) $PN BP36
J 2
(-6885 5835);
DISPLAY 0.489362 (-6885 5835);
PAINT MONO (-6885 5835);
FORCEPROP 0 LASTPIN (-6875 5775) $PN BP39
J 2
(-6885 5785);
DISPLAY 0.489362 (-6885 5785);
PAINT MONO (-6885 5785);
FORCEPROP 0 LASTPIN (-6875 5725) $PN BP41
J 2
(-6885 5735);
DISPLAY 0.489362 (-6885 5735);
PAINT MONO (-6885 5735);
FORCEPROP 0 LASTPIN (-6875 5675) $PN BP43
J 2
(-6885 5685);
DISPLAY 0.489362 (-6885 5685);
PAINT MONO (-6885 5685);
FORCEPROP 0 LASTPIN (-6875 5625) $PN BP45
J 2
(-6885 5635);
DISPLAY 0.489362 (-6885 5635);
PAINT MONO (-6885 5635);
FORCEPROP 0 LASTPIN (-6875 5575) $PN BP47
J 2
(-6885 5585);
DISPLAY 0.489362 (-6885 5585);
PAINT MONO (-6885 5585);
FORCEPROP 0 LASTPIN (-6875 5525) $PN BP49
J 2
(-6885 5535);
DISPLAY 0.489362 (-6885 5535);
PAINT MONO (-6885 5535);
FORCEPROP 0 LASTPIN (-6875 5475) $PN BR23
J 2
(-6885 5485);
DISPLAY 0.489362 (-6885 5485);
PAINT MONO (-6885 5485);
FORCEPROP 0 LASTPIN (-6875 5425) $PN BR25
J 2
(-6885 5435);
DISPLAY 0.489362 (-6885 5435);
PAINT MONO (-6885 5435);
FORCEPROP 0 LASTPIN (-6875 5375) $PN BR27
J 2
(-6885 5385);
DISPLAY 0.489362 (-6885 5385);
PAINT MONO (-6885 5385);
FORCEPROP 0 LASTPIN (-6875 5325) $PN BR29
J 2
(-6885 5335);
DISPLAY 0.489362 (-6885 5335);
PAINT MONO (-6885 5335);
FORCEPROP 0 LASTPIN (-6875 5275) $PN BR31
J 2
(-6885 5285);
DISPLAY 0.489362 (-6885 5285);
PAINT MONO (-6885 5285);
FORCEPROP 0 LASTPIN (-6875 5225) $PN BR33
J 2
(-6885 5235);
DISPLAY 0.489362 (-6885 5235);
PAINT MONO (-6885 5235);
FORCEPROP 0 LASTPIN (-6875 5175) $PN BR35
J 2
(-6885 5185);
DISPLAY 0.489362 (-6885 5185);
PAINT MONO (-6885 5185);
FORCEPROP 0 LASTPIN (-6875 5125) $PN BR40
J 2
(-6885 5135);
DISPLAY 0.489362 (-6885 5135);
PAINT MONO (-6885 5135);
FORCEPROP 0 LASTPIN (-6875 5075) $PN BR42
J 2
(-6885 5085);
DISPLAY 0.489362 (-6885 5085);
PAINT MONO (-6885 5085);
FORCEPROP 0 LASTPIN (-6875 5025) $PN BR44
J 2
(-6885 5035);
DISPLAY 0.489362 (-6885 5035);
PAINT MONO (-6885 5035);
FORCEPROP 0 LASTPIN (-6875 4975) $PN BR46
J 2
(-6885 4985);
DISPLAY 0.489362 (-6885 4985);
PAINT MONO (-6885 4985);
FORCEPROP 0 LASTPIN (-6875 4925) $PN BR48
J 2
(-6885 4935);
DISPLAY 0.489362 (-6885 4935);
PAINT MONO (-6885 4935);
FORCEPROP 0 LASTPIN (-6875 4875) $PN BR50
J 2
(-6885 4885);
DISPLAY 0.489362 (-6885 4885);
PAINT MONO (-6885 4885);
FORCEPROP 0 LASTPIN (-6875 4825) $PN BR52
J 2
(-6885 4835);
DISPLAY 0.489362 (-6885 4835);
PAINT MONO (-6885 4835);
FORCEPROP 0 LASTPIN (-6875 4775) $PN BT23
J 2
(-6885 4785);
DISPLAY 0.489362 (-6885 4785);
PAINT MONO (-6885 4785);
FORCEPROP 0 LASTPIN (-6875 4725) $PN BT24
J 2
(-6885 4735);
DISPLAY 0.489362 (-6885 4735);
PAINT MONO (-6885 4735);
FORCEPROP 0 LASTPIN (-6875 4675) $PN BT26
J 2
(-6885 4685);
DISPLAY 0.489362 (-6885 4685);
PAINT MONO (-6885 4685);
FORCEPROP 0 LASTPIN (-6875 4625) $PN BT27
J 2
(-6885 4635);
DISPLAY 0.489362 (-6885 4635);
PAINT MONO (-6885 4635);
FORCEPROP 0 LASTPIN (-6875 4575) $PN BT29
J 2
(-6885 4585);
DISPLAY 0.489362 (-6885 4585);
PAINT MONO (-6885 4585);
FORCEPROP 0 LASTPIN (-6875 4525) $PN BT30
J 2
(-6885 4535);
DISPLAY 0.489362 (-6885 4535);
PAINT MONO (-6885 4535);
FORCEPROP 0 LASTPIN (-6875 4475) $PN BT32
J 2
(-6885 4485);
DISPLAY 0.489362 (-6885 4485);
PAINT MONO (-6885 4485);
FORCEPROP 0 LASTPIN (-6875 4425) $PN BT33
J 2
(-6885 4435);
DISPLAY 0.489362 (-6885 4435);
PAINT MONO (-6885 4435);
FORCEPROP 0 LASTPIN (-6875 4375) $PN BT43
J 2
(-6885 4385);
DISPLAY 0.489362 (-6885 4385);
PAINT MONO (-6885 4385);
FORCEPROP 0 LASTPIN (-6875 4325) $PN BT44
J 2
(-6885 4335);
DISPLAY 0.489362 (-6885 4335);
PAINT MONO (-6885 4335);
FORCEPROP 0 LASTPIN (-6875 4275) $PN BT46
J 2
(-6885 4285);
DISPLAY 0.489362 (-6885 4285);
PAINT MONO (-6885 4285);
FORCEPROP 0 LASTPIN (-6875 4225) $PN BT47
J 2
(-6885 4235);
DISPLAY 0.489362 (-6885 4235);
PAINT MONO (-6885 4235);
FORCEPROP 0 LASTPIN (-6875 4175) $PN BT49
J 2
(-6885 4185);
DISPLAY 0.489362 (-6885 4185);
PAINT MONO (-6885 4185);
FORCEPROP 0 LASTPIN (-6875 4125) $PN BT50
J 2
(-6885 4135);
DISPLAY 0.489362 (-6885 4135);
PAINT MONO (-6885 4135);
FORCEPROP 0 LASTPIN (-6875 4075) $PN BT52
J 2
(-6885 4085);
DISPLAY 0.489362 (-6885 4085);
PAINT MONO (-6885 4085);
FORCEPROP 0 LASTPIN (-6875 4025) $PN BT53
J 2
(-6885 4035);
DISPLAY 0.489362 (-6885 4035);
PAINT MONO (-6885 4035);
FORCEPROP 0 LASTPIN (-6875 3975) $PN BW35
J 2
(-6885 3985);
DISPLAY 0.489362 (-6885 3985);
PAINT MONO (-6885 3985);
FORCEPROP 0 LASTPIN (-6875 3925) $PN BW36
J 2
(-6885 3935);
DISPLAY 0.489362 (-6885 3935);
PAINT MONO (-6885 3935);
FORCEPROP 0 LASTPIN (-6875 3875) $PN BW40
J 2
(-6885 3885);
DISPLAY 0.489362 (-6885 3885);
PAINT MONO (-6885 3885);
FORCEPROP 0 LASTPIN (-6875 3825) $PN BW41
J 2
(-6885 3835);
DISPLAY 0.489362 (-6885 3835);
PAINT MONO (-6885 3835);
FORCEPROP 0 LASTPIN (-6875 3775) $PN BY23
J 2
(-6885 3785);
DISPLAY 0.489362 (-6885 3785);
PAINT MONO (-6885 3785);
FORCEPROP 0 LASTPIN (-6875 3725) $PN BY24
J 2
(-6885 3735);
DISPLAY 0.489362 (-6885 3735);
PAINT MONO (-6885 3735);
FORCEPROP 0 LASTPIN (-6875 3675) $PN BY26
J 2
(-6885 3685);
DISPLAY 0.489362 (-6885 3685);
PAINT MONO (-6885 3685);
FORCEPROP 0 LASTPIN (-6875 3625) $PN BY27
J 2
(-6885 3635);
DISPLAY 0.489362 (-6885 3635);
PAINT MONO (-6885 3635);
FORCEPROP 0 LASTPIN (-6875 3575) $PN BY29
J 2
(-6885 3585);
DISPLAY 0.489362 (-6885 3585);
PAINT MONO (-6885 3585);
FORCEPROP 0 LASTPIN (-6875 3525) $PN BY30
J 2
(-6885 3535);
DISPLAY 0.489362 (-6885 3535);
PAINT MONO (-6885 3535);
FORCEPROP 0 LASTPIN (-6875 3475) $PN BY32
J 2
(-6885 3485);
DISPLAY 0.489362 (-6885 3485);
PAINT MONO (-6885 3485);
FORCEPROP 0 LASTPIN (-6875 3425) $PN BY33
J 2
(-6885 3435);
DISPLAY 0.489362 (-6885 3435);
PAINT MONO (-6885 3435);
FORCEPROP 0 LASTPIN (-6875 3375) $PN BY43
J 2
(-6885 3385);
DISPLAY 0.489362 (-6885 3385);
PAINT MONO (-6885 3385);
FORCEPROP 0 LASTPIN (-6875 3325) $PN BY44
J 2
(-6885 3335);
DISPLAY 0.489362 (-6885 3335);
PAINT MONO (-6885 3335);
FORCEPROP 0 LASTPIN (-6875 3275) $PN BY46
J 2
(-6885 3285);
DISPLAY 0.489362 (-6885 3285);
PAINT MONO (-6885 3285);
FORCEPROP 0 LASTPIN (-6875 3225) $PN BY47
J 2
(-6885 3235);
DISPLAY 0.489362 (-6885 3235);
PAINT MONO (-6885 3235);
FORCEPROP 0 LASTPIN (-6875 3175) $PN BY49
J 2
(-6885 3185);
DISPLAY 0.489362 (-6885 3185);
PAINT MONO (-6885 3185);
FORCEPROP 0 LASTPIN (-6875 3125) $PN BY50
J 2
(-6885 3135);
DISPLAY 0.489362 (-6885 3135);
PAINT MONO (-6885 3135);
FORCEPROP 0 LASTPIN (-6875 3075) $PN BY52
J 2
(-6885 3085);
DISPLAY 0.489362 (-6885 3085);
PAINT MONO (-6885 3085);
FORCEPROP 0 LASTPIN (-6875 3025) $PN BY53
J 2
(-6885 3035);
DISPLAY 0.489362 (-6885 3035);
PAINT MONO (-6885 3035);
FORCEPROP 0 LASTPIN (-6875 2975) $PN CC35
J 2
(-6885 2985);
DISPLAY 0.489362 (-6885 2985);
PAINT MONO (-6885 2985);
FORCEPROP 0 LASTPIN (-6875 2925) $PN CC36
J 2
(-6885 2935);
DISPLAY 0.489362 (-6885 2935);
PAINT MONO (-6885 2935);
FORCEPROP 0 LASTPIN (-6875 2875) $PN CC40
J 2
(-6885 2885);
DISPLAY 0.489362 (-6885 2885);
PAINT MONO (-6885 2885);
FORCEPROP 0 LASTPIN (-6875 2825) $PN CC41
J 2
(-6885 2835);
DISPLAY 0.489362 (-6885 2835);
PAINT MONO (-6885 2835);
FORCEPROP 0 LASTPIN (-6875 2775) $PN CD23
J 2
(-6885 2785);
DISPLAY 0.489362 (-6885 2785);
PAINT MONO (-6885 2785);
FORCEPROP 0 LASTPIN (-6875 2725) $PN CD24
J 2
(-6885 2735);
DISPLAY 0.489362 (-6885 2735);
PAINT MONO (-6885 2735);
FORCEPROP 0 LASTPIN (-6875 2675) $PN CD26
J 2
(-6885 2685);
DISPLAY 0.489362 (-6885 2685);
PAINT MONO (-6885 2685);
FORCEPROP 0 LASTPIN (-6875 2625) $PN CD27
J 2
(-6885 2635);
DISPLAY 0.489362 (-6885 2635);
PAINT MONO (-6885 2635);
FORCEPROP 0 LASTPIN (-6875 2575) $PN CD29
J 2
(-6885 2585);
DISPLAY 0.489362 (-6885 2585);
PAINT MONO (-6885 2585);
FORCEPROP 0 LASTPIN (-6875 2525) $PN CD30
J 2
(-6885 2535);
DISPLAY 0.489362 (-6885 2535);
PAINT MONO (-6885 2535);
FORCEPROP 0 LASTPIN (-6875 2475) $PN CD32
J 2
(-6885 2485);
DISPLAY 0.489362 (-6885 2485);
PAINT MONO (-6885 2485);
FORCEPROP 0 LASTPIN (-6875 2425) $PN CD33
J 2
(-6885 2435);
DISPLAY 0.489362 (-6885 2435);
PAINT MONO (-6885 2435);
FORCEPROP 0 LASTPIN (-6875 2375) $PN CD43
J 2
(-6885 2385);
DISPLAY 0.489362 (-6885 2385);
PAINT MONO (-6885 2385);
FORCEPROP 0 LASTPIN (-6875 2325) $PN CD44
J 2
(-6885 2335);
DISPLAY 0.489362 (-6885 2335);
PAINT MONO (-6885 2335);
FORCEPROP 0 LASTPIN (-6875 2275) $PN CD46
J 2
(-6885 2285);
DISPLAY 0.489362 (-6885 2285);
PAINT MONO (-6885 2285);
FORCEPROP 0 LASTPIN (-6875 2225) $PN CD47
J 2
(-6885 2235);
DISPLAY 0.489362 (-6885 2235);
PAINT MONO (-6885 2235);
FORCEPROP 0 LASTPIN (-6875 2175) $PN CD49
J 2
(-6885 2185);
DISPLAY 0.489362 (-6885 2185);
PAINT MONO (-6885 2185);
FORCEPROP 0 LASTPIN (-6875 2125) $PN CD50
J 2
(-6885 2135);
DISPLAY 0.489362 (-6885 2135);
PAINT MONO (-6885 2135);
FORCEPROP 0 LASTPIN (-6875 2075) $PN CD52
J 2
(-6885 2085);
DISPLAY 0.489362 (-6885 2085);
PAINT MONO (-6885 2085);
FORCEPROP 0 LASTPIN (-6875 2025) $PN CD53
J 2
(-6885 2035);
DISPLAY 0.489362 (-6885 2035);
PAINT MONO (-6885 2035);
FORCEPROP 0 LASTPIN (-6875 1975) $PN CG35
J 2
(-6885 1985);
DISPLAY 0.489362 (-6885 1985);
PAINT MONO (-6885 1985);
FORCEPROP 0 LASTPIN (-6875 1925) $PN CG36
J 2
(-6885 1935);
DISPLAY 0.489362 (-6885 1935);
PAINT MONO (-6885 1935);
FORCEPROP 0 LASTPIN (-6875 1875) $PN CG40
J 2
(-6885 1885);
DISPLAY 0.489362 (-6885 1885);
PAINT MONO (-6885 1885);
FORCEPROP 0 LASTPIN (-6875 1825) $PN CG41
J 2
(-6885 1835);
DISPLAY 0.489362 (-6885 1835);
PAINT MONO (-6885 1835);
FORCEPROP 0 LASTPIN (-6875 1775) $PN CH23
J 2
(-6885 1785);
DISPLAY 0.489362 (-6885 1785);
PAINT MONO (-6885 1785);
FORCEPROP 0 LASTPIN (-6875 1725) $PN CH24
J 2
(-6885 1735);
DISPLAY 0.489362 (-6885 1735);
PAINT MONO (-6885 1735);
FORCEPROP 0 LASTPIN (-6875 1675) $PN CH26
J 2
(-6885 1685);
DISPLAY 0.489362 (-6885 1685);
PAINT MONO (-6885 1685);
FORCEPROP 0 LASTPIN (-6875 1625) $PN CH27
J 2
(-6885 1635);
DISPLAY 0.489362 (-6885 1635);
PAINT MONO (-6885 1635);
FORCEPROP 0 LASTPIN (-6875 1575) $PN CH29
J 2
(-6885 1585);
DISPLAY 0.489362 (-6885 1585);
PAINT MONO (-6885 1585);
FORCEPROP 0 LASTPIN (-6875 1525) $PN CH30
J 2
(-6885 1535);
DISPLAY 0.489362 (-6885 1535);
PAINT MONO (-6885 1535);
FORCEPROP 0 LASTPIN (-6875 1475) $PN CH32
J 2
(-6885 1485);
DISPLAY 0.489362 (-6885 1485);
PAINT MONO (-6885 1485);
FORCEPROP 0 LASTPIN (-6875 1425) $PN CH33
J 2
(-6885 1435);
DISPLAY 0.489362 (-6885 1435);
PAINT MONO (-6885 1435);
FORCEPROP 0 LASTPIN (-6875 1375) $PN CH43
J 2
(-6885 1385);
DISPLAY 0.489362 (-6885 1385);
PAINT MONO (-6885 1385);
FORCEPROP 0 LASTPIN (-6875 1325) $PN CH44
J 2
(-6885 1335);
DISPLAY 0.489362 (-6885 1335);
PAINT MONO (-6885 1335);
FORCEPROP 0 LASTPIN (-6875 1275) $PN CH46
J 2
(-6885 1285);
DISPLAY 0.489362 (-6885 1285);
PAINT MONO (-6885 1285);
FORCEPROP 0 LASTPIN (-6875 1225) $PN CH47
J 2
(-6885 1235);
DISPLAY 0.489362 (-6885 1235);
PAINT MONO (-6885 1235);
FORCEPROP 0 LASTPIN (-6875 1175) $PN CH49
J 2
(-6885 1185);
DISPLAY 0.489362 (-6885 1185);
PAINT MONO (-6885 1185);
FORCEPROP 0 LASTPIN (-6875 1125) $PN CH50
J 2
(-6885 1135);
DISPLAY 0.489362 (-6885 1135);
PAINT MONO (-6885 1135);
FORCEPROP 0 LASTPIN (-6875 1075) $PN CH52
J 2
(-6885 1085);
DISPLAY 0.489362 (-6885 1085);
PAINT MONO (-6885 1085);
FORCEPROP 0 LASTPIN (-6875 1025) $PN CH53
J 2
(-6885 1035);
DISPLAY 0.489362 (-6885 1035);
PAINT MONO (-6885 1035);
FORCEPROP 0 LASTPIN (-6875 975) $PN CK35
J 2
(-6885 985);
DISPLAY 0.489362 (-6885 985);
PAINT MONO (-6885 985);
FORCEPROP 0 LASTPIN (-6875 925) $PN CK36
J 2
(-6885 935);
DISPLAY 0.489362 (-6885 935);
PAINT MONO (-6885 935);
FORCEPROP 0 LASTPIN (-6875 875) $PN CK40
J 2
(-6885 885);
DISPLAY 0.489362 (-6885 885);
PAINT MONO (-6885 885);
FORCEPROP 0 LASTPIN (-6875 825) $PN CK41
J 2
(-6885 835);
DISPLAY 0.489362 (-6885 835);
PAINT MONO (-6885 835);
FORCEPROP 0 LASTPIN (-6875 775) $PN CL29
J 2
(-6885 785);
DISPLAY 0.489362 (-6885 785);
PAINT MONO (-6885 785);
FORCEPROP 0 LASTPIN (-6875 725) $PN CL30
J 2
(-6885 735);
DISPLAY 0.489362 (-6885 735);
PAINT MONO (-6885 735);
FORCEPROP 0 LASTPIN (-5575 6425) $PN CL32
J 0
(-5565 6435);
DISPLAY 0.489362 (-5565 6435);
PAINT MONO (-5565 6435);
FORCEPROP 0 LASTPIN (-5575 6375) $PN CL33
J 0
(-5565 6385);
DISPLAY 0.489362 (-5565 6385);
PAINT MONO (-5565 6385);
FORCEPROP 0 LASTPIN (-5575 6325) $PN CL43
J 0
(-5565 6335);
DISPLAY 0.489362 (-5565 6335);
PAINT MONO (-5565 6335);
FORCEPROP 0 LASTPIN (-5575 6275) $PN CL44
J 0
(-5565 6285);
DISPLAY 0.489362 (-5565 6285);
PAINT MONO (-5565 6285);
FORCEPROP 0 LASTPIN (-5575 6225) $PN CL46
J 0
(-5565 6235);
DISPLAY 0.489362 (-5565 6235);
PAINT MONO (-5565 6235);
FORCEPROP 0 LASTPIN (-5575 6175) $PN CL47
J 0
(-5565 6185);
DISPLAY 0.489362 (-5565 6185);
PAINT MONO (-5565 6185);
FORCEPROP 0 LASTPIN (-5575 6125) $PN CN35
J 0
(-5565 6135);
DISPLAY 0.489362 (-5565 6135);
PAINT MONO (-5565 6135);
FORCEPROP 0 LASTPIN (-5575 6075) $PN CN36
J 0
(-5565 6085);
DISPLAY 0.489362 (-5565 6085);
PAINT MONO (-5565 6085);
FORCEPROP 0 LASTPIN (-5575 6025) $PN CN40
J 0
(-5565 6035);
DISPLAY 0.489362 (-5565 6035);
PAINT MONO (-5565 6035);
FORCEPROP 0 LASTPIN (-5575 5975) $PN CN41
J 0
(-5565 5985);
DISPLAY 0.489362 (-5565 5985);
PAINT MONO (-5565 5985);
FORCEPROP 0 LASTPIN (-5575 5925) $PN CP23
J 0
(-5565 5935);
DISPLAY 0.489362 (-5565 5935);
PAINT MONO (-5565 5935);
FORCEPROP 0 LASTPIN (-5575 5875) $PN CP24
J 0
(-5565 5885);
DISPLAY 0.489362 (-5565 5885);
PAINT MONO (-5565 5885);
FORCEPROP 0 LASTPIN (-5575 5825) $PN CP26
J 0
(-5565 5835);
DISPLAY 0.489362 (-5565 5835);
PAINT MONO (-5565 5835);
FORCEPROP 0 LASTPIN (-5575 5775) $PN CP27
J 0
(-5565 5785);
DISPLAY 0.489362 (-5565 5785);
PAINT MONO (-5565 5785);
FORCEPROP 0 LASTPIN (-5575 5725) $PN CP29
J 0
(-5565 5735);
DISPLAY 0.489362 (-5565 5735);
PAINT MONO (-5565 5735);
FORCEPROP 0 LASTPIN (-5575 5675) $PN CP30
J 0
(-5565 5685);
DISPLAY 0.489362 (-5565 5685);
PAINT MONO (-5565 5685);
FORCEPROP 0 LASTPIN (-5575 5625) $PN CP32
J 0
(-5565 5635);
DISPLAY 0.489362 (-5565 5635);
PAINT MONO (-5565 5635);
FORCEPROP 0 LASTPIN (-5575 5575) $PN CP33
J 0
(-5565 5585);
DISPLAY 0.489362 (-5565 5585);
PAINT MONO (-5565 5585);
FORCEPROP 0 LASTPIN (-5575 5525) $PN CP43
J 0
(-5565 5535);
DISPLAY 0.489362 (-5565 5535);
PAINT MONO (-5565 5535);
FORCEPROP 0 LASTPIN (-5575 5475) $PN CP44
J 0
(-5565 5485);
DISPLAY 0.489362 (-5565 5485);
PAINT MONO (-5565 5485);
FORCEPROP 0 LASTPIN (-5575 5425) $PN CP46
J 0
(-5565 5435);
DISPLAY 0.489362 (-5565 5435);
PAINT MONO (-5565 5435);
FORCEPROP 0 LASTPIN (-5575 5375) $PN CP47
J 0
(-5565 5385);
DISPLAY 0.489362 (-5565 5385);
PAINT MONO (-5565 5385);
FORCEPROP 0 LASTPIN (-5575 5325) $PN CP49
J 0
(-5565 5335);
DISPLAY 0.489362 (-5565 5335);
PAINT MONO (-5565 5335);
FORCEPROP 0 LASTPIN (-5575 5275) $PN CP50
J 0
(-5565 5285);
DISPLAY 0.489362 (-5565 5285);
PAINT MONO (-5565 5285);
FORCEPROP 0 LASTPIN (-5575 5225) $PN CP52
J 0
(-5565 5235);
DISPLAY 0.489362 (-5565 5235);
PAINT MONO (-5565 5235);
FORCEPROP 0 LASTPIN (-5575 5175) $PN CP53
J 0
(-5565 5185);
DISPLAY 0.489362 (-5565 5185);
PAINT MONO (-5565 5185);
FORCEPROP 0 LASTPIN (-5575 5125) $PN CU35
J 0
(-5565 5135);
DISPLAY 0.489362 (-5565 5135);
PAINT MONO (-5565 5135);
FORCEPROP 0 LASTPIN (-5575 5075) $PN CU36
J 0
(-5565 5085);
DISPLAY 0.489362 (-5565 5085);
PAINT MONO (-5565 5085);
FORCEPROP 0 LASTPIN (-5575 5025) $PN CU40
J 0
(-5565 5035);
DISPLAY 0.489362 (-5565 5035);
PAINT MONO (-5565 5035);
FORCEPROP 0 LASTPIN (-5575 4975) $PN CU41
J 0
(-5565 4985);
DISPLAY 0.489362 (-5565 4985);
PAINT MONO (-5565 4985);
FORCEPROP 0 LASTPIN (-5575 4925) $PN CV23
J 0
(-5565 4935);
DISPLAY 0.489362 (-5565 4935);
PAINT MONO (-5565 4935);
FORCEPROP 0 LASTPIN (-5575 4875) $PN CV24
J 0
(-5565 4885);
DISPLAY 0.489362 (-5565 4885);
PAINT MONO (-5565 4885);
FORCEPROP 0 LASTPIN (-5575 4825) $PN CV26
J 0
(-5565 4835);
DISPLAY 0.489362 (-5565 4835);
PAINT MONO (-5565 4835);
FORCEPROP 0 LASTPIN (-5575 4775) $PN CV27
J 0
(-5565 4785);
DISPLAY 0.489362 (-5565 4785);
PAINT MONO (-5565 4785);
FORCEPROP 0 LASTPIN (-5575 4725) $PN CV29
J 0
(-5565 4735);
DISPLAY 0.489362 (-5565 4735);
PAINT MONO (-5565 4735);
FORCEPROP 0 LASTPIN (-5575 4675) $PN CV30
J 0
(-5565 4685);
DISPLAY 0.489362 (-5565 4685);
PAINT MONO (-5565 4685);
FORCEPROP 0 LASTPIN (-5575 4625) $PN CV32
J 0
(-5565 4635);
DISPLAY 0.489362 (-5565 4635);
PAINT MONO (-5565 4635);
FORCEPROP 0 LASTPIN (-5575 4575) $PN CV33
J 0
(-5565 4585);
DISPLAY 0.489362 (-5565 4585);
PAINT MONO (-5565 4585);
FORCEPROP 0 LASTPIN (-5575 4525) $PN CV43
J 0
(-5565 4535);
DISPLAY 0.489362 (-5565 4535);
PAINT MONO (-5565 4535);
FORCEPROP 0 LASTPIN (-5575 4475) $PN CV44
J 0
(-5565 4485);
DISPLAY 0.489362 (-5565 4485);
PAINT MONO (-5565 4485);
FORCEPROP 0 LASTPIN (-5575 4425) $PN CV46
J 0
(-5565 4435);
DISPLAY 0.489362 (-5565 4435);
PAINT MONO (-5565 4435);
FORCEPROP 0 LASTPIN (-5575 4375) $PN CV47
J 0
(-5565 4385);
DISPLAY 0.489362 (-5565 4385);
PAINT MONO (-5565 4385);
FORCEPROP 0 LASTPIN (-5575 4325) $PN CV49
J 0
(-5565 4335);
DISPLAY 0.489362 (-5565 4335);
PAINT MONO (-5565 4335);
FORCEPROP 0 LASTPIN (-5575 4275) $PN CV50
J 0
(-5565 4285);
DISPLAY 0.489362 (-5565 4285);
PAINT MONO (-5565 4285);
FORCEPROP 0 LASTPIN (-5575 4225) $PN CV52
J 0
(-5565 4235);
DISPLAY 0.489362 (-5565 4235);
PAINT MONO (-5565 4235);
FORCEPROP 0 LASTPIN (-5575 4175) $PN CV53
J 0
(-5565 4185);
DISPLAY 0.489362 (-5565 4185);
PAINT MONO (-5565 4185);
FORCEPROP 0 LASTPIN (-5575 4125) $PN DA35
J 0
(-5565 4135);
DISPLAY 0.489362 (-5565 4135);
PAINT MONO (-5565 4135);
FORCEPROP 0 LASTPIN (-5575 4075) $PN DA36
J 0
(-5565 4085);
DISPLAY 0.489362 (-5565 4085);
PAINT MONO (-5565 4085);
FORCEPROP 0 LASTPIN (-5575 4025) $PN DA40
J 0
(-5565 4035);
DISPLAY 0.489362 (-5565 4035);
PAINT MONO (-5565 4035);
FORCEPROP 0 LASTPIN (-5575 3975) $PN DA41
J 0
(-5565 3985);
DISPLAY 0.489362 (-5565 3985);
PAINT MONO (-5565 3985);
FORCEPROP 0 LASTPIN (-5575 3925) $PN DB23
J 0
(-5565 3935);
DISPLAY 0.489362 (-5565 3935);
PAINT MONO (-5565 3935);
FORCEPROP 0 LASTPIN (-5575 3875) $PN DB24
J 0
(-5565 3885);
DISPLAY 0.489362 (-5565 3885);
PAINT MONO (-5565 3885);
FORCEPROP 0 LASTPIN (-5575 3825) $PN DB26
J 0
(-5565 3835);
DISPLAY 0.489362 (-5565 3835);
PAINT MONO (-5565 3835);
FORCEPROP 0 LASTPIN (-5575 3775) $PN DB27
J 0
(-5565 3785);
DISPLAY 0.489362 (-5565 3785);
PAINT MONO (-5565 3785);
FORCEPROP 0 LASTPIN (-5575 3725) $PN DB29
J 0
(-5565 3735);
DISPLAY 0.489362 (-5565 3735);
PAINT MONO (-5565 3735);
FORCEPROP 0 LASTPIN (-5575 3675) $PN DB30
J 0
(-5565 3685);
DISPLAY 0.489362 (-5565 3685);
PAINT MONO (-5565 3685);
FORCEPROP 0 LASTPIN (-5575 3625) $PN DB32
J 0
(-5565 3635);
DISPLAY 0.489362 (-5565 3635);
PAINT MONO (-5565 3635);
FORCEPROP 0 LASTPIN (-5575 3575) $PN DB33
J 0
(-5565 3585);
DISPLAY 0.489362 (-5565 3585);
PAINT MONO (-5565 3585);
FORCEPROP 0 LASTPIN (-5575 3525) $PN DB43
J 0
(-5565 3535);
DISPLAY 0.489362 (-5565 3535);
PAINT MONO (-5565 3535);
FORCEPROP 0 LASTPIN (-5575 3475) $PN DB44
J 0
(-5565 3485);
DISPLAY 0.489362 (-5565 3485);
PAINT MONO (-5565 3485);
FORCEPROP 0 LASTPIN (-5575 3425) $PN DB46
J 0
(-5565 3435);
DISPLAY 0.489362 (-5565 3435);
PAINT MONO (-5565 3435);
FORCEPROP 0 LASTPIN (-5575 3375) $PN DB47
J 0
(-5565 3385);
DISPLAY 0.489362 (-5565 3385);
PAINT MONO (-5565 3385);
FORCEPROP 0 LASTPIN (-5575 3325) $PN DB49
J 0
(-5565 3335);
DISPLAY 0.489362 (-5565 3335);
PAINT MONO (-5565 3335);
FORCEPROP 0 LASTPIN (-5575 3275) $PN DB50
J 0
(-5565 3285);
DISPLAY 0.489362 (-5565 3285);
PAINT MONO (-5565 3285);
FORCEPROP 0 LASTPIN (-5575 3225) $PN DB52
J 0
(-5565 3235);
DISPLAY 0.489362 (-5565 3235);
PAINT MONO (-5565 3235);
FORCEPROP 0 LASTPIN (-5575 3175) $PN DB53
J 0
(-5565 3185);
DISPLAY 0.489362 (-5565 3185);
PAINT MONO (-5565 3185);
FORCEPROP 0 LASTPIN (-5575 3125) $PN DC35
J 0
(-5565 3135);
DISPLAY 0.489362 (-5565 3135);
PAINT MONO (-5565 3135);
FORCEPROP 0 LASTPIN (-5575 3075) $PN DC36
J 0
(-5565 3085);
DISPLAY 0.489362 (-5565 3085);
PAINT MONO (-5565 3085);
FORCEPROP 0 LASTPIN (-5575 3025) $PN DC40
J 0
(-5565 3035);
DISPLAY 0.489362 (-5565 3035);
PAINT MONO (-5565 3035);
FORCEPROP 0 LASTPIN (-5575 2975) $PN DC41
J 0
(-5565 2985);
DISPLAY 0.489362 (-5565 2985);
PAINT MONO (-5565 2985);
FORCEPROP 0 LASTPIN (-5575 2925) $PN DD22
J 0
(-5565 2935);
DISPLAY 0.489362 (-5565 2935);
PAINT MONO (-5565 2935);
FORCEPROP 0 LASTPIN (-5575 2875) $PN DD25
J 0
(-5565 2885);
DISPLAY 0.489362 (-5565 2885);
PAINT MONO (-5565 2885);
FORCEPROP 0 LASTPIN (-5575 2825) $PN DD28
J 0
(-5565 2835);
DISPLAY 0.489362 (-5565 2835);
PAINT MONO (-5565 2835);
FORCEPROP 0 LASTPIN (-5575 2775) $PN DD31
J 0
(-5565 2785);
DISPLAY 0.489362 (-5565 2785);
PAINT MONO (-5565 2785);
FORCEPROP 0 LASTPIN (-5575 2725) $PN DD34
J 0
(-5565 2735);
DISPLAY 0.489362 (-5565 2735);
PAINT MONO (-5565 2735);
FORCEPROP 0 LASTPIN (-5575 2675) $PN DD42
J 0
(-5565 2685);
DISPLAY 0.489362 (-5565 2685);
PAINT MONO (-5565 2685);
FORCEPROP 0 LASTPIN (-5575 2625) $PN DD45
J 0
(-5565 2635);
DISPLAY 0.489362 (-5565 2635);
PAINT MONO (-5565 2635);
FORCEPROP 0 LASTPIN (-5575 2575) $PN DD48
J 0
(-5565 2585);
DISPLAY 0.489362 (-5565 2585);
PAINT MONO (-5565 2585);
FORCEPROP 0 LASTPIN (-5575 2525) $PN DD51
J 0
(-5565 2535);
DISPLAY 0.489362 (-5565 2535);
PAINT MONO (-5565 2535);
FORCEPROP 0 LASTPIN (-5575 2475) $PN DD54
J 0
(-5565 2485);
DISPLAY 0.489362 (-5565 2485);
PAINT MONO (-5565 2485);
FORCEPROP 0 LASTPIN (-5575 2425) $PN DE22
J 0
(-5565 2435);
DISPLAY 0.489362 (-5565 2435);
PAINT MONO (-5565 2435);
FORCEPROP 0 LASTPIN (-5575 2375) $PN DE25
J 0
(-5565 2385);
DISPLAY 0.489362 (-5565 2385);
PAINT MONO (-5565 2385);
FORCEPROP 0 LASTPIN (-5575 2325) $PN DE28
J 0
(-5565 2335);
DISPLAY 0.489362 (-5565 2335);
PAINT MONO (-5565 2335);
FORCEPROP 0 LASTPIN (-5575 2275) $PN DE31
J 0
(-5565 2285);
DISPLAY 0.489362 (-5565 2285);
PAINT MONO (-5565 2285);
FORCEPROP 0 LASTPIN (-5575 2225) $PN DE34
J 0
(-5565 2235);
DISPLAY 0.489362 (-5565 2235);
PAINT MONO (-5565 2235);
FORCEPROP 0 LASTPIN (-5575 2175) $PN DE35
J 0
(-5565 2185);
DISPLAY 0.489362 (-5565 2185);
PAINT MONO (-5565 2185);
FORCEPROP 0 LASTPIN (-5575 2125) $PN DE41
J 0
(-5565 2135);
DISPLAY 0.489362 (-5565 2135);
PAINT MONO (-5565 2135);
FORCEPROP 0 LASTPIN (-5575 2075) $PN DE42
J 0
(-5565 2085);
DISPLAY 0.489362 (-5565 2085);
PAINT MONO (-5565 2085);
FORCEPROP 0 LASTPIN (-5575 2025) $PN DE45
J 0
(-5565 2035);
DISPLAY 0.489362 (-5565 2035);
PAINT MONO (-5565 2035);
FORCEPROP 0 LASTPIN (-5575 1975) $PN DE48
J 0
(-5565 1985);
DISPLAY 0.489362 (-5565 1985);
PAINT MONO (-5565 1985);
FORCEPROP 0 LASTPIN (-5575 1925) $PN DE51
J 0
(-5565 1935);
DISPLAY 0.489362 (-5565 1935);
PAINT MONO (-5565 1935);
FORCEPROP 0 LASTPIN (-5575 1875) $PN DE54
J 0
(-5565 1885);
DISPLAY 0.489362 (-5565 1885);
PAINT MONO (-5565 1885);
FORCEPROP 0 LASTPIN (-5575 1825) $PN DG19
J 0
(-5565 1835);
DISPLAY 0.489362 (-5565 1835);
PAINT MONO (-5565 1835);
FORCEPROP 0 LASTPIN (-5575 1775) $PN DG57
J 0
(-5565 1785);
DISPLAY 0.489362 (-5565 1785);
PAINT MONO (-5565 1785);
FORCEPROP 0 LASTPIN (-5575 1725) $PN DH19
J 0
(-5565 1735);
DISPLAY 0.489362 (-5565 1735);
PAINT MONO (-5565 1735);
FORCEPROP 0 LASTPIN (-5575 1675) $PN DH20
J 0
(-5565 1685);
DISPLAY 0.489362 (-5565 1685);
PAINT MONO (-5565 1685);
FORCEPROP 0 LASTPIN (-5575 1625) $PN DH22
J 0
(-5565 1635);
DISPLAY 0.489362 (-5565 1635);
PAINT MONO (-5565 1635);
FORCEPROP 0 LASTPIN (-5575 1575) $PN DH23
J 0
(-5565 1585);
DISPLAY 0.489362 (-5565 1585);
PAINT MONO (-5565 1585);
FORCEPROP 0 LASTPIN (-5575 1525) $PN DH25
J 0
(-5565 1535);
DISPLAY 0.489362 (-5565 1535);
PAINT MONO (-5565 1535);
FORCEPROP 0 LASTPIN (-5575 1475) $PN DH26
J 0
(-5565 1485);
DISPLAY 0.489362 (-5565 1485);
PAINT MONO (-5565 1485);
FORCEPROP 0 LASTPIN (-5575 1425) $PN DH28
J 0
(-5565 1435);
DISPLAY 0.489362 (-5565 1435);
PAINT MONO (-5565 1435);
FORCEPROP 0 LASTPIN (-5575 1375) $PN DH29
J 0
(-5565 1385);
DISPLAY 0.489362 (-5565 1385);
PAINT MONO (-5565 1385);
FORCEPROP 0 LASTPIN (-5575 1325) $PN DH31
J 0
(-5565 1335);
DISPLAY 0.489362 (-5565 1335);
PAINT MONO (-5565 1335);
FORCEPROP 0 LASTPIN (-5575 1275) $PN DH32
J 0
(-5565 1285);
DISPLAY 0.489362 (-5565 1285);
PAINT MONO (-5565 1285);
FORCEPROP 0 LASTPIN (-5575 1225) $PN DH34
J 0
(-5565 1235);
DISPLAY 0.489362 (-5565 1235);
PAINT MONO (-5565 1235);
FORCEPROP 0 LASTPIN (-5575 1175) $PN DH35
J 0
(-5565 1185);
DISPLAY 0.489362 (-5565 1185);
PAINT MONO (-5565 1185);
FORCEPROP 0 LASTPIN (-5575 1125) $PN DH41
J 0
(-5565 1135);
DISPLAY 0.489362 (-5565 1135);
PAINT MONO (-5565 1135);
FORCEPROP 0 LASTPIN (-5575 1075) $PN DH42
J 0
(-5565 1085);
DISPLAY 0.489362 (-5565 1085);
PAINT MONO (-5565 1085);
FORCEPROP 0 LASTPIN (-5575 1025) $PN DH44
J 0
(-5565 1035);
DISPLAY 0.489362 (-5565 1035);
PAINT MONO (-5565 1035);
FORCEPROP 0 LASTPIN (-5575 975) $PN DH45
J 0
(-5565 985);
DISPLAY 0.489362 (-5565 985);
PAINT MONO (-5565 985);
FORCEPROP 0 LASTPIN (-5575 925) $PN DH47
J 0
(-5565 935);
DISPLAY 0.489362 (-5565 935);
PAINT MONO (-5565 935);
FORCEPROP 0 LASTPIN (-5575 875) $PN DH48
J 0
(-5565 885);
DISPLAY 0.489362 (-5565 885);
PAINT MONO (-5565 885);
FORCEPROP 0 LASTPIN (-5575 825) $PN DH50
J 0
(-5565 835);
DISPLAY 0.489362 (-5565 835);
PAINT MONO (-5565 835);
FORCEPROP 0 LASTPIN (-5575 775) $PN DH51
J 0
(-5565 785);
DISPLAY 0.489362 (-5565 785);
PAINT MONO (-5565 785);
FORCEPROP 0 LASTPIN (-5575 725) $PN DH53
J 0
(-5565 735);
DISPLAY 0.489362 (-5565 735);
PAINT MONO (-5565 735);
FORCEPROP 0 LASTPIN (-5575 675) $PN DH54
J 0
(-5565 685);
DISPLAY 0.489362 (-5565 685);
PAINT MONO (-5565 685);
FORCEPROP 0 LASTPIN (-5575 625) $PN DH56
J 0
(-5565 635);
DISPLAY 0.489362 (-5565 635);
PAINT MONO (-5565 635);
FORCEPROP 0 LASTPIN (-5575 575) $PN DH57
J 0
(-5565 585);
DISPLAY 0.489362 (-5565 585);
PAINT MONO (-5565 585);
FORCEPROP 2 LAST PART_TYPE SMLF
J 0
(-6650 6675);
DISPLAY 1.021277 (-6650 6675);
FORCEPROP 1 LAST PART_NUMBER DGA^6000030
J 0
(-6725 6650);
DISPLAY 0.489362 (-6725 6650);
PAINT SKYBLUE (-6725 6650);
FORCEPROP 1 LAST MATERIAL IO
J 0
(-6720 6607);
DISPLAY 0.489362 (-6720 6607);
PAINT SKYBLUE (-6720 6607);
FORCEPROP 2 LAST VALUE SOCKET6096_13568-001
J 0
(-6625 6600);
DISPLAY 0.489362 (-6625 6600);
PAINT SKYBLUE (-6625 6600);
FORCEPROP 2 LAST CDS_LIB pure_quanta
J 0
(-6225 3375);
DISPLAY INVISIBLE (-6225 3375);
FORCEPROP 1 LAST CDS_LMAN_SYM_OUTLINE -500,3200,500,-3200
J 0
(-6225 3375);
DISPLAY 0.468085 (-6225 3375);
PAINT GREEN (-6225 3375);
DISPLAY INVISIBLE (-6225 3375);
FORCEPROP 1 LAST NEEDS_NO_SIZE TRUE
J 0
(-6225 3375);
DISPLAY 0.723404 (-6225 3375);
PAINT GREEN (-6225 3375);
DISPLAY INVISIBLE (-6225 3375);
FORCEPROP 1 LAST PATH I32
J 0
(-6225 3375);
DISPLAY 0.723404 (-6225 3375);
PAINT GREEN (-6225 3375);
DISPLAY INVISIBLE (-6225 3375);
FORCEADD VCC_CORE..1
(-2050 6575);
FORCEPROP 3 LASTPIN (-2050 6525) SIG_NAME PVDDIO_P1\g
J 0
(-2040 6535);
DISPLAY 0.659574 (-2040 6535);
PAINT MONO (-2040 6535);
DISPLAY INVISIBLE (-2040 6535);
FORCEPROP 1 LAST HDL_POWER PVDDIO_P1
J 1
(-2050 6625);
DISPLAY 0.489362 (-2050 6625);
PAINT GREEN (-2050 6625);
FORCEPROP 2 LAST CDS_LIB pure_quanta_power
J 0
(-2050 6575);
DISPLAY INVISIBLE (-2050 6575);
FORCEPROP 1 LAST PATH I36
J 0
(-2000 6600);
DISPLAY 0.872340 (-2000 6600);
PAINT AQUA (-2000 6600);
DISPLAY INVISIBLE (-2000 6600);
FORCEADD UNIVERSAL_POWER..1
(-1125 950);
FORCEPROP 3 LASTPIN (-1125 900) SIG_NAME PVDD18_S5_P1\g
J 0
(-1115 910);
DISPLAY 0.659574 (-1115 910);
PAINT MONO (-1115 910);
DISPLAY INVISIBLE (-1115 910);
FORCEPROP 1 LAST HDL_POWER PVDD18_S5_P1
J 1
(-1125 1000);
DISPLAY 0.489362 (-1125 1000);
PAINT GREEN (-1125 1000);
FORCEPROP 2 LAST CDS_LIB pure_quanta_power
J 0
(-1125 950);
DISPLAY INVISIBLE (-1125 950);
FORCEPROP 1 LAST PATH I37
J 0
(-1075 975);
DISPLAY 0.872340 (-1075 975);
PAINT AQUA (-1075 975);
DISPLAY INVISIBLE (-1075 975);
FORCEADD UNIVERSAL_POWER..1
(-1450 950);
FORCEPROP 3 LASTPIN (-1450 900) SIG_NAME P1V5_BAT\g
J 0
(-1440 910);
DISPLAY 0.659574 (-1440 910);
PAINT MONO (-1440 910);
DISPLAY INVISIBLE (-1440 910);
FORCEPROP 1 LAST HDL_POWER P1V5_BAT
J 1
(-1450 1000);
DISPLAY 0.489362 (-1450 1000);
PAINT GREEN (-1450 1000);
FORCEPROP 2 LAST CDS_LIB pure_quanta_power
J 0
(-1450 950);
DISPLAY INVISIBLE (-1450 950);
FORCEPROP 1 LAST PATH I38
J 0
(-1400 975);
DISPLAY 0.872340 (-1400 975);
PAINT AQUA (-1400 975);
DISPLAY INVISIBLE (-1400 975);
FORCEADD VCC_CORE..1
(-3550 6575);
FORCEPROP 3 LASTPIN (-3550 6525) SIG_NAME PVDD11_S3_P1\g
J 0
(-3540 6535);
DISPLAY 0.659574 (-3540 6535);
PAINT MONO (-3540 6535);
DISPLAY INVISIBLE (-3540 6535);
FORCEPROP 1 LAST HDL_POWER PVDD11_S3_P1
J 1
(-3550 6625);
DISPLAY 0.489362 (-3550 6625);
PAINT GREEN (-3550 6625);
FORCEPROP 2 LAST CDS_LIB pure_quanta_power
J 0
(-3550 6575);
DISPLAY INVISIBLE (-3550 6575);
FORCEPROP 1 LAST PATH I41
J 0
(-3500 6600);
DISPLAY 0.872340 (-3500 6600);
PAINT AQUA (-3500 6600);
DISPLAY INVISIBLE (-3500 6600);
FORCEADD UNIVERSAL_POWER..1
(-3725 2700);
FORCEPROP 3 LASTPIN (-3725 2650) SIG_NAME PVDD18_S5_P1\g
J 0
(-3715 2660);
DISPLAY 0.659574 (-3715 2660);
PAINT MONO (-3715 2660);
DISPLAY INVISIBLE (-3715 2660);
FORCEPROP 1 LAST HDL_POWER PVDD18_S5_P1
J 1
(-3725 2750);
DISPLAY 0.489362 (-3725 2750);
PAINT GREEN (-3725 2750);
FORCEPROP 2 LAST CDS_LIB pure_quanta_power
J 0
(-3725 2700);
DISPLAY INVISIBLE (-3725 2700);
FORCEPROP 1 LAST PATH I42
J 0
(-3675 2725);
DISPLAY 0.872340 (-3675 2725);
PAINT AQUA (-3675 2725);
DISPLAY INVISIBLE (-3675 2725);
FORCEADD UNIVERSAL_POWER..1
(-3725 1050);
FORCEPROP 3 LASTPIN (-3725 1000) SIG_NAME PVDD_33_S5\g
J 0
(-3715 1010);
DISPLAY 0.659574 (-3715 1010);
PAINT MONO (-3715 1010);
DISPLAY INVISIBLE (-3715 1010);
FORCEPROP 1 LAST HDL_POWER PVDD_33_S5
J 1
(-3725 1100);
DISPLAY 0.489362 (-3725 1100);
PAINT GREEN (-3725 1100);
FORCEPROP 2 LAST CDS_LIB pure_quanta_power
J 0
(-3725 1050);
DISPLAY INVISIBLE (-3725 1050);
FORCEPROP 1 LAST PATH I44
J 0
(-3675 1075);
DISPLAY 0.872340 (-3675 1075);
PAINT AQUA (-3675 1075);
DISPLAY INVISIBLE (-3675 1075);
FORCEADD GENOA_SP5..27
(-2800 3500);
FORCEPROP 1 LAST LOCATION U26
J 0
(-3300 6700);
DISPLAY 0.489362 (-3300 6700);
PAINT SKYBLUE (-3300 6700);
FORCEPROP 0 LAST $SEC 27
J 0
(-3275 6925);
DISPLAY 0.680851 (-3275 6925);
PAINT MONO (-3275 6925);
DISPLAY INVISIBLE (-3275 6925);
FORCEPROP 0 LAST CDS_SEC 27
J 0
(-3275 6925);
DISPLAY 1.021277 (-3275 6925);
DISPLAY INVISIBLE (-3275 6925);
FORCEPROP 0 LASTPIN (-3450 6475) $PN BJ18
J 2
(-3460 6485);
DISPLAY 0.489362 (-3460 6485);
PAINT MONO (-3460 6485);
FORCEPROP 0 LASTPIN (-3450 6425) $PN BJ23
J 2
(-3460 6435);
DISPLAY 0.489362 (-3460 6435);
PAINT MONO (-3460 6435);
FORCEPROP 0 LASTPIN (-3450 6375) $PN BJ25
J 2
(-3460 6385);
DISPLAY 0.489362 (-3460 6385);
PAINT MONO (-3460 6385);
FORCEPROP 0 LASTPIN (-3450 6325) $PN BJ27
J 2
(-3460 6335);
DISPLAY 0.489362 (-3460 6335);
PAINT MONO (-3460 6335);
FORCEPROP 0 LASTPIN (-3450 6275) $PN BK22
J 2
(-3460 6285);
DISPLAY 0.489362 (-3460 6285);
PAINT MONO (-3460 6285);
FORCEPROP 0 LASTPIN (-3450 6225) $PN BK24
J 2
(-3460 6235);
DISPLAY 0.489362 (-3460 6235);
PAINT MONO (-3460 6235);
FORCEPROP 0 LASTPIN (-3450 6175) $PN BK26
J 2
(-3460 6185);
DISPLAY 0.489362 (-3460 6185);
PAINT MONO (-3460 6185);
FORCEPROP 0 LASTPIN (-3450 6125) $PN BK28
J 2
(-3460 6135);
DISPLAY 0.489362 (-3460 6135);
PAINT MONO (-3460 6135);
FORCEPROP 0 LASTPIN (-3450 6075) $PN BK49
J 2
(-3460 6085);
DISPLAY 0.489362 (-3460 6085);
PAINT MONO (-3460 6085);
FORCEPROP 0 LASTPIN (-3450 6025) $PN BL23
J 2
(-3460 6035);
DISPLAY 0.489362 (-3460 6035);
PAINT MONO (-3460 6035);
FORCEPROP 0 LASTPIN (-3450 5975) $PN BL25
J 2
(-3460 5985);
DISPLAY 0.489362 (-3460 5985);
PAINT MONO (-3460 5985);
FORCEPROP 0 LASTPIN (-3450 5925) $PN BL27
J 2
(-3460 5935);
DISPLAY 0.489362 (-3460 5935);
PAINT MONO (-3460 5935);
FORCEPROP 0 LASTPIN (-3450 5875) $PN BL48
J 2
(-3460 5885);
DISPLAY 0.489362 (-3460 5885);
PAINT MONO (-3460 5885);
FORCEPROP 0 LASTPIN (-3450 5825) $PN BM12
J 2
(-3460 5835);
DISPLAY 0.489362 (-3460 5835);
PAINT MONO (-3460 5835);
FORCEPROP 0 LASTPIN (-3450 5775) $PN BM19
J 2
(-3460 5785);
DISPLAY 0.489362 (-3460 5785);
PAINT MONO (-3460 5785);
FORCEPROP 0 LASTPIN (-3450 5725) $PN BM22
J 2
(-3460 5735);
DISPLAY 0.489362 (-3460 5735);
PAINT MONO (-3460 5735);
FORCEPROP 0 LASTPIN (-3450 5675) $PN BM24
J 2
(-3460 5685);
DISPLAY 0.489362 (-3460 5685);
PAINT MONO (-3460 5685);
FORCEPROP 0 LASTPIN (-3450 5625) $PN BM26
J 2
(-3460 5635);
DISPLAY 0.489362 (-3460 5635);
PAINT MONO (-3460 5635);
FORCEPROP 0 LASTPIN (-3450 5575) $PN BM28
J 2
(-3460 5585);
DISPLAY 0.489362 (-3460 5585);
PAINT MONO (-3460 5585);
FORCEPROP 0 LASTPIN (-3450 5525) $PN BM30
J 2
(-3460 5535);
DISPLAY 0.489362 (-3460 5535);
PAINT MONO (-3460 5535);
FORCEPROP 0 LASTPIN (-3450 5475) $PN BM32
J 2
(-3460 5485);
DISPLAY 0.489362 (-3460 5485);
PAINT MONO (-3460 5485);
FORCEPROP 0 LASTPIN (-3450 5425) $PN BM34
J 2
(-3460 5435);
DISPLAY 0.489362 (-3460 5435);
PAINT MONO (-3460 5435);
FORCEPROP 0 LASTPIN (-3450 5375) $PN BM36
J 2
(-3460 5385);
DISPLAY 0.489362 (-3460 5385);
PAINT MONO (-3460 5385);
FORCEPROP 0 LASTPIN (-3450 5325) $PN BM39
J 2
(-3460 5335);
DISPLAY 0.489362 (-3460 5335);
PAINT MONO (-3460 5335);
FORCEPROP 0 LASTPIN (-3450 5275) $PN BM41
J 2
(-3460 5285);
DISPLAY 0.489362 (-3460 5285);
PAINT MONO (-3460 5285);
FORCEPROP 0 LASTPIN (-3450 5225) $PN BM43
J 2
(-3460 5235);
DISPLAY 0.489362 (-3460 5235);
PAINT MONO (-3460 5235);
FORCEPROP 0 LASTPIN (-3450 5175) $PN BM45
J 2
(-3460 5185);
DISPLAY 0.489362 (-3460 5185);
PAINT MONO (-3460 5185);
FORCEPROP 0 LASTPIN (-3450 5125) $PN BM47
J 2
(-3460 5135);
DISPLAY 0.489362 (-3460 5135);
PAINT MONO (-3460 5135);
FORCEPROP 0 LASTPIN (-3450 5075) $PN BM49
J 2
(-3460 5085);
DISPLAY 0.489362 (-3460 5085);
PAINT MONO (-3460 5085);
FORCEPROP 0 LASTPIN (-3450 5025) $PN BN25
J 2
(-3460 5035);
DISPLAY 0.489362 (-3460 5035);
PAINT MONO (-3460 5035);
FORCEPROP 0 LASTPIN (-3450 4975) $PN BN29
J 2
(-3460 4985);
DISPLAY 0.489362 (-3460 4985);
PAINT MONO (-3460 4985);
FORCEPROP 0 LASTPIN (-3450 4925) $PN BN33
J 2
(-3460 4935);
DISPLAY 0.489362 (-3460 4935);
PAINT MONO (-3460 4935);
FORCEPROP 0 LASTPIN (-3450 4875) $PN BN40
J 2
(-3460 4885);
DISPLAY 0.489362 (-3460 4885);
PAINT MONO (-3460 4885);
FORCEPROP 0 LASTPIN (-3450 4825) $PN BN44
J 2
(-3460 4835);
DISPLAY 0.489362 (-3460 4835);
PAINT MONO (-3460 4835);
FORCEPROP 0 LASTPIN (-3450 4775) $PN BN48
J 2
(-3460 4785);
DISPLAY 0.489362 (-3460 4785);
PAINT MONO (-3460 4785);
FORCEPROP 0 LASTPIN (-3450 4725) $PN BP22
J 2
(-3460 4735);
DISPLAY 0.489362 (-3460 4735);
PAINT MONO (-3460 4735);
FORCEPROP 0 LASTPIN (-3450 4675) $PN BR4
J 2
(-3460 4685);
DISPLAY 0.489362 (-3460 4685);
PAINT MONO (-3460 4685);
FORCEPROP 0 LASTPIN (-3450 4625) $PN BR11
J 2
(-3460 4635);
DISPLAY 0.489362 (-3460 4635);
PAINT MONO (-3460 4635);
FORCEPROP 0 LASTPIN (-3450 4575) $PN BR18
J 2
(-3460 4585);
DISPLAY 0.489362 (-3460 4585);
PAINT MONO (-3460 4585);
FORCEPROP 0 LASTPIN (-3450 4525) $PN BV5
J 2
(-3460 4535);
DISPLAY 0.489362 (-3460 4535);
PAINT MONO (-3460 4535);
FORCEPROP 0 LASTPIN (-3450 4475) $PN BV12
J 2
(-3460 4485);
DISPLAY 0.489362 (-3460 4485);
PAINT MONO (-3460 4485);
FORCEPROP 0 LASTPIN (-3450 4425) $PN BV19
J 2
(-3460 4435);
DISPLAY 0.489362 (-3460 4435);
PAINT MONO (-3460 4435);
FORCEPROP 0 LASTPIN (-3450 4375) $PN BV22
J 2
(-3460 4385);
DISPLAY 0.489362 (-3460 4385);
PAINT MONO (-3460 4385);
FORCEPROP 0 LASTPIN (-3450 4325) $PN CA4
J 2
(-3460 4335);
DISPLAY 0.489362 (-3460 4335);
PAINT MONO (-3460 4335);
FORCEPROP 0 LASTPIN (-3450 4275) $PN CA11
J 2
(-3460 4285);
DISPLAY 0.489362 (-3460 4285);
PAINT MONO (-3460 4285);
FORCEPROP 0 LASTPIN (-3450 4225) $PN CA18
J 2
(-3460 4235);
DISPLAY 0.489362 (-3460 4235);
PAINT MONO (-3460 4235);
FORCEPROP 0 LASTPIN (-3450 4175) $PN CB22
J 2
(-3460 4185);
DISPLAY 0.489362 (-3460 4185);
PAINT MONO (-3460 4185);
FORCEPROP 0 LASTPIN (-3450 4125) $PN CD5
J 2
(-3460 4135);
DISPLAY 0.489362 (-3460 4135);
PAINT MONO (-3460 4135);
FORCEPROP 0 LASTPIN (-3450 4075) $PN CD12
J 2
(-3460 4085);
DISPLAY 0.489362 (-3460 4085);
PAINT MONO (-3460 4085);
FORCEPROP 0 LASTPIN (-3450 4025) $PN CD19
J 2
(-3460 4035);
DISPLAY 0.489362 (-3460 4035);
PAINT MONO (-3460 4035);
FORCEPROP 0 LASTPIN (-3450 3975) $PN CF22
J 2
(-3460 3985);
DISPLAY 0.489362 (-3460 3985);
PAINT MONO (-3460 3985);
FORCEPROP 0 LASTPIN (-3450 3925) $PN CG4
J 2
(-3460 3935);
DISPLAY 0.489362 (-3460 3935);
PAINT MONO (-3460 3935);
FORCEPROP 0 LASTPIN (-3450 3875) $PN CG11
J 2
(-3460 3885);
DISPLAY 0.489362 (-3460 3885);
PAINT MONO (-3460 3885);
FORCEPROP 0 LASTPIN (-3450 3825) $PN CG18
J 2
(-3460 3835);
DISPLAY 0.489362 (-3460 3835);
PAINT MONO (-3460 3835);
FORCEPROP 0 LASTPIN (-3450 3775) $PN CJ22
J 2
(-3460 3785);
DISPLAY 0.489362 (-3460 3785);
PAINT MONO (-3460 3785);
FORCEPROP 0 LASTPIN (-3450 3725) $PN CK5
J 2
(-3460 3735);
DISPLAY 0.489362 (-3460 3735);
PAINT MONO (-3460 3735);
FORCEPROP 0 LASTPIN (-3450 3675) $PN CK12
J 2
(-3460 3685);
DISPLAY 0.489362 (-3460 3685);
PAINT MONO (-3460 3685);
FORCEPROP 0 LASTPIN (-3450 3625) $PN CK19
J 2
(-3460 3635);
DISPLAY 0.489362 (-3460 3635);
PAINT MONO (-3460 3635);
FORCEPROP 0 LASTPIN (-3450 3575) $PN CM22
J 2
(-3460 3585);
DISPLAY 0.489362 (-3460 3585);
PAINT MONO (-3460 3585);
FORCEPROP 0 LASTPIN (-3450 3525) $PN CN4
J 2
(-3460 3535);
DISPLAY 0.489362 (-3460 3535);
PAINT MONO (-3460 3535);
FORCEPROP 0 LASTPIN (-3450 3475) $PN CN11
J 2
(-3460 3485);
DISPLAY 0.489362 (-3460 3485);
PAINT MONO (-3460 3485);
FORCEPROP 0 LASTPIN (-3450 3425) $PN CN18
J 2
(-3460 3435);
DISPLAY 0.489362 (-3460 3435);
PAINT MONO (-3460 3435);
FORCEPROP 0 LASTPIN (-3450 3375) $PN CT5
J 2
(-3460 3385);
DISPLAY 0.489362 (-3460 3385);
PAINT MONO (-3460 3385);
FORCEPROP 0 LASTPIN (-3450 3325) $PN CT12
J 2
(-3460 3335);
DISPLAY 0.489362 (-3460 3335);
PAINT MONO (-3460 3335);
FORCEPROP 0 LASTPIN (-3450 3275) $PN CT19
J 2
(-3460 3285);
DISPLAY 0.489362 (-3460 3285);
PAINT MONO (-3460 3285);
FORCEPROP 0 LASTPIN (-3450 3225) $PN CT22
J 2
(-3460 3235);
DISPLAY 0.489362 (-3460 3235);
PAINT MONO (-3460 3235);
FORCEPROP 0 LASTPIN (-3450 3175) $PN CW4
J 2
(-3460 3185);
DISPLAY 0.489362 (-3460 3185);
PAINT MONO (-3460 3185);
FORCEPROP 0 LASTPIN (-3450 3125) $PN CW11
J 2
(-3460 3135);
DISPLAY 0.489362 (-3460 3135);
PAINT MONO (-3460 3135);
FORCEPROP 0 LASTPIN (-3450 3075) $PN CW18
J 2
(-3460 3085);
DISPLAY 0.489362 (-3460 3085);
PAINT MONO (-3460 3085);
FORCEPROP 0 LASTPIN (-3450 3025) $PN CY22
J 2
(-3460 3035);
DISPLAY 0.489362 (-3460 3035);
PAINT MONO (-3460 3035);
FORCEPROP 0 LASTPIN (-3450 2975) $PN DB5
J 2
(-3460 2985);
DISPLAY 0.489362 (-3460 2985);
PAINT MONO (-3460 2985);
FORCEPROP 0 LASTPIN (-3450 2925) $PN DB12
J 2
(-3460 2935);
DISPLAY 0.489362 (-3460 2935);
PAINT MONO (-3460 2935);
FORCEPROP 0 LASTPIN (-3450 2875) $PN DB19
J 2
(-3460 2885);
DISPLAY 0.489362 (-3460 2885);
PAINT MONO (-3460 2885);
FORCEPROP 0 LASTPIN (-3450 2825) $PN DE4
J 2
(-3460 2835);
DISPLAY 0.489362 (-3460 2835);
PAINT MONO (-3460 2835);
FORCEPROP 0 LASTPIN (-3450 2775) $PN DE11
J 2
(-3460 2785);
DISPLAY 0.489362 (-3460 2785);
PAINT MONO (-3460 2785);
FORCEPROP 0 LASTPIN (-3450 2725) $PN DE18
J 2
(-3460 2735);
DISPLAY 0.489362 (-3460 2735);
PAINT MONO (-3460 2735);
FORCEPROP 0 LASTPIN (-3450 2675) $PN DG5
J 2
(-3460 2685);
DISPLAY 0.489362 (-3460 2685);
PAINT MONO (-3460 2685);
FORCEPROP 0 LASTPIN (-3450 2475) $PN AR52
J 2
(-3460 2485);
DISPLAY 0.489362 (-3460 2485);
PAINT MONO (-3460 2485);
FORCEPROP 0 LASTPIN (-3450 2425) $PN AR54
J 2
(-3460 2435);
DISPLAY 0.489362 (-3460 2435);
PAINT MONO (-3460 2435);
FORCEPROP 0 LASTPIN (-3450 2375) $PN AT51
J 2
(-3460 2385);
DISPLAY 0.489362 (-3460 2385);
PAINT MONO (-3460 2385);
FORCEPROP 0 LASTPIN (-3450 2325) $PN AT53
J 2
(-3460 2335);
DISPLAY 0.489362 (-3460 2335);
PAINT MONO (-3460 2335);
FORCEPROP 0 LASTPIN (-3450 2275) $PN AU50
J 2
(-3460 2285);
DISPLAY 0.489362 (-3460 2285);
PAINT MONO (-3460 2285);
FORCEPROP 0 LASTPIN (-3450 2225) $PN AU52
J 2
(-3460 2235);
DISPLAY 0.489362 (-3460 2235);
PAINT MONO (-3460 2235);
FORCEPROP 0 LASTPIN (-3450 1125) $PN AU54
J 2
(-3460 1135);
DISPLAY 0.489362 (-3460 1135);
PAINT MONO (-3460 1135);
FORCEPROP 0 LASTPIN (-3450 2175) $PN AV49
J 2
(-3460 2185);
DISPLAY 0.489362 (-3460 2185);
PAINT MONO (-3460 2185);
FORCEPROP 0 LASTPIN (-3450 2125) $PN AV51
J 2
(-3460 2135);
DISPLAY 0.489362 (-3460 2135);
PAINT MONO (-3460 2135);
FORCEPROP 0 LASTPIN (-3450 2075) $PN AV53
J 2
(-3460 2085);
DISPLAY 0.489362 (-3460 2085);
PAINT MONO (-3460 2085);
FORCEPROP 0 LASTPIN (-3450 2025) $PN AW50
J 2
(-3460 2035);
DISPLAY 0.489362 (-3460 2035);
PAINT MONO (-3460 2035);
FORCEPROP 0 LASTPIN (-3450 1975) $PN AW52
J 2
(-3460 1985);
DISPLAY 0.489362 (-3460 1985);
PAINT MONO (-3460 1985);
FORCEPROP 0 LASTPIN (-3450 1925) $PN AW54
J 2
(-3460 1935);
DISPLAY 0.489362 (-3460 1935);
PAINT MONO (-3460 1935);
FORCEPROP 0 LASTPIN (-3450 1875) $PN AY51
J 2
(-3460 1885);
DISPLAY 0.489362 (-3460 1885);
PAINT MONO (-3460 1885);
FORCEPROP 0 LASTPIN (-3450 1825) $PN AY53
J 2
(-3460 1835);
DISPLAY 0.489362 (-3460 1835);
PAINT MONO (-3460 1835);
FORCEPROP 0 LASTPIN (-3450 1775) $PN BA50
J 2
(-3460 1785);
DISPLAY 0.489362 (-3460 1785);
PAINT MONO (-3460 1785);
FORCEPROP 0 LASTPIN (-3450 1725) $PN BA52
J 2
(-3460 1735);
DISPLAY 0.489362 (-3460 1735);
PAINT MONO (-3460 1735);
FORCEPROP 0 LASTPIN (-3450 1675) $PN BA54
J 2
(-3460 1685);
DISPLAY 0.489362 (-3460 1685);
PAINT MONO (-3460 1685);
FORCEPROP 0 LASTPIN (-3450 1625) $PN BB51
J 2
(-3460 1635);
DISPLAY 0.489362 (-3460 1635);
PAINT MONO (-3460 1635);
FORCEPROP 0 LASTPIN (-3450 1575) $PN BB53
J 2
(-3460 1585);
DISPLAY 0.489362 (-3460 1585);
PAINT MONO (-3460 1585);
FORCEPROP 0 LASTPIN (-3450 1525) $PN BC52
J 2
(-3460 1535);
DISPLAY 0.489362 (-3460 1535);
PAINT MONO (-3460 1535);
FORCEPROP 0 LASTPIN (-3450 1475) $PN BC54
J 2
(-3460 1485);
DISPLAY 0.489362 (-3460 1485);
PAINT MONO (-3460 1485);
FORCEPROP 0 LASTPIN (-3450 875) $PN BN52
J 2
(-3460 885);
DISPLAY 0.489362 (-3460 885);
PAINT MONO (-3460 885);
FORCEPROP 0 LASTPIN (-3450 825) $PN BP51
J 2
(-3460 835);
DISPLAY 0.489362 (-3460 835);
PAINT MONO (-3460 835);
FORCEPROP 0 LASTPIN (-2150 575) $PN BN23
J 0
(-2140 585);
DISPLAY 0.489362 (-2140 585);
PAINT MONO (-2140 585);
FORCEPROP 0 LASTPIN (-2150 5575) $PN AA54
J 0
(-2140 5585);
DISPLAY 0.489362 (-2140 5585);
PAINT MONO (-2140 5585);
FORCEPROP 0 LASTPIN (-2150 5525) $PN AC58
J 0
(-2140 5535);
DISPLAY 0.489362 (-2140 5535);
PAINT MONO (-2140 5535);
FORCEPROP 0 LASTPIN (-2150 5475) $PN AC65
J 0
(-2140 5485);
DISPLAY 0.489362 (-2140 5485);
PAINT MONO (-2140 5485);
FORCEPROP 0 LASTPIN (-2150 5425) $PN AC72
J 0
(-2140 5435);
DISPLAY 0.489362 (-2140 5435);
PAINT MONO (-2140 5435);
FORCEPROP 0 LASTPIN (-2150 5375) $PN AD54
J 0
(-2140 5385);
DISPLAY 0.489362 (-2140 5385);
PAINT MONO (-2140 5385);
FORCEPROP 0 LASTPIN (-2150 5325) $PN AF57
J 0
(-2140 5335);
DISPLAY 0.489362 (-2140 5335);
PAINT MONO (-2140 5335);
FORCEPROP 0 LASTPIN (-2150 5275) $PN AF64
J 0
(-2140 5285);
DISPLAY 0.489362 (-2140 5285);
PAINT MONO (-2140 5285);
FORCEPROP 0 LASTPIN (-2150 5225) $PN AF71
J 0
(-2140 5235);
DISPLAY 0.489362 (-2140 5235);
PAINT MONO (-2140 5235);
FORCEPROP 0 LASTPIN (-2150 5175) $PN AH54
J 0
(-2140 5185);
DISPLAY 0.489362 (-2140 5185);
PAINT MONO (-2140 5185);
FORCEPROP 0 LASTPIN (-2150 5125) $PN AJ58
J 0
(-2140 5135);
DISPLAY 0.489362 (-2140 5135);
PAINT MONO (-2140 5135);
FORCEPROP 0 LASTPIN (-2150 5075) $PN AJ65
J 0
(-2140 5085);
DISPLAY 0.489362 (-2140 5085);
PAINT MONO (-2140 5085);
FORCEPROP 0 LASTPIN (-2150 5025) $PN AJ72
J 0
(-2140 5035);
DISPLAY 0.489362 (-2140 5035);
PAINT MONO (-2140 5035);
FORCEPROP 0 LASTPIN (-2150 4975) $PN AM54
J 0
(-2140 4985);
DISPLAY 0.489362 (-2140 4985);
PAINT MONO (-2140 4985);
FORCEPROP 0 LASTPIN (-2150 4925) $PN AM57
J 0
(-2140 4935);
DISPLAY 0.489362 (-2140 4935);
PAINT MONO (-2140 4935);
FORCEPROP 0 LASTPIN (-2150 4875) $PN AM64
J 0
(-2140 4885);
DISPLAY 0.489362 (-2140 4885);
PAINT MONO (-2140 4885);
FORCEPROP 0 LASTPIN (-2150 4825) $PN AM71
J 0
(-2140 4835);
DISPLAY 0.489362 (-2140 4835);
PAINT MONO (-2140 4835);
FORCEPROP 0 LASTPIN (-2150 4775) $PN AR58
J 0
(-2140 4785);
DISPLAY 0.489362 (-2140 4785);
PAINT MONO (-2140 4785);
FORCEPROP 0 LASTPIN (-2150 4725) $PN AR65
J 0
(-2140 4735);
DISPLAY 0.489362 (-2140 4735);
PAINT MONO (-2140 4735);
FORCEPROP 0 LASTPIN (-2150 4675) $PN AR72
J 0
(-2140 4685);
DISPLAY 0.489362 (-2140 4685);
PAINT MONO (-2140 4685);
FORCEPROP 0 LASTPIN (-3450 2575) $PN BH27
J 2
(-3460 2585);
DISPLAY 0.489362 (-3460 2585);
PAINT MONO (-3460 2585);
FORCEPROP 0 LASTPIN (-2150 4625) $PN AV57
J 0
(-2140 4635);
DISPLAY 0.489362 (-2140 4635);
PAINT MONO (-2140 4635);
FORCEPROP 0 LASTPIN (-2150 4575) $PN AV64
J 0
(-2140 4585);
DISPLAY 0.489362 (-2140 4585);
PAINT MONO (-2140 4585);
FORCEPROP 0 LASTPIN (-2150 4525) $PN AV71
J 0
(-2140 4535);
DISPLAY 0.489362 (-2140 4535);
PAINT MONO (-2140 4535);
FORCEPROP 0 LASTPIN (-2150 4475) $PN BA58
J 0
(-2140 4485);
DISPLAY 0.489362 (-2140 4485);
PAINT MONO (-2140 4485);
FORCEPROP 0 LASTPIN (-2150 4425) $PN BA65
J 0
(-2140 4435);
DISPLAY 0.489362 (-2140 4435);
PAINT MONO (-2140 4435);
FORCEPROP 0 LASTPIN (-2150 4375) $PN BA72
J 0
(-2140 4385);
DISPLAY 0.489362 (-2140 4385);
PAINT MONO (-2140 4385);
FORCEPROP 0 LASTPIN (-2150 4325) $PN BD50
J 0
(-2140 4335);
DISPLAY 0.489362 (-2140 4335);
PAINT MONO (-2140 4335);
FORCEPROP 0 LASTPIN (-2150 4275) $PN BD52
J 0
(-2140 4285);
DISPLAY 0.489362 (-2140 4285);
PAINT MONO (-2140 4285);
FORCEPROP 0 LASTPIN (-2150 4225) $PN BD54
J 0
(-2140 4235);
DISPLAY 0.489362 (-2140 4235);
PAINT MONO (-2140 4235);
FORCEPROP 0 LASTPIN (-2150 4175) $PN BF51
J 0
(-2140 4185);
DISPLAY 0.489362 (-2140 4185);
PAINT MONO (-2140 4185);
FORCEPROP 0 LASTPIN (-2150 4125) $PN BF53
J 0
(-2140 4135);
DISPLAY 0.489362 (-2140 4135);
PAINT MONO (-2140 4135);
FORCEPROP 0 LASTPIN (-2150 4075) $PN BF57
J 0
(-2140 4085);
DISPLAY 0.489362 (-2140 4085);
PAINT MONO (-2140 4085);
FORCEPROP 0 LASTPIN (-2150 4025) $PN BF64
J 0
(-2140 4035);
DISPLAY 0.489362 (-2140 4035);
PAINT MONO (-2140 4035);
FORCEPROP 0 LASTPIN (-2150 3975) $PN BF71
J 0
(-2140 3985);
DISPLAY 0.489362 (-2140 3985);
PAINT MONO (-2140 3985);
FORCEPROP 0 LASTPIN (-2150 3925) $PN BG50
J 0
(-2140 3935);
DISPLAY 0.489362 (-2140 3935);
PAINT MONO (-2140 3935);
FORCEPROP 0 LASTPIN (-2150 3875) $PN BG52
J 0
(-2140 3885);
DISPLAY 0.489362 (-2140 3885);
PAINT MONO (-2140 3885);
FORCEPROP 0 LASTPIN (-2150 3825) $PN BG54
J 0
(-2140 3835);
DISPLAY 0.489362 (-2140 3835);
PAINT MONO (-2140 3835);
FORCEPROP 0 LASTPIN (-2150 3775) $PN BH51
J 0
(-2140 3785);
DISPLAY 0.489362 (-2140 3785);
PAINT MONO (-2140 3785);
FORCEPROP 0 LASTPIN (-2150 3725) $PN BH53
J 0
(-2140 3735);
DISPLAY 0.489362 (-2140 3735);
PAINT MONO (-2140 3735);
FORCEPROP 0 LASTPIN (-2150 3675) $PN BJ50
J 0
(-2140 3685);
DISPLAY 0.489362 (-2140 3685);
PAINT MONO (-2140 3685);
FORCEPROP 0 LASTPIN (-2150 3625) $PN BJ52
J 0
(-2140 3635);
DISPLAY 0.489362 (-2140 3635);
PAINT MONO (-2140 3635);
FORCEPROP 0 LASTPIN (-2150 3575) $PN BJ54
J 0
(-2140 3585);
DISPLAY 0.489362 (-2140 3585);
PAINT MONO (-2140 3585);
FORCEPROP 0 LASTPIN (-2150 3525) $PN BJ58
J 0
(-2140 3535);
DISPLAY 0.489362 (-2140 3535);
PAINT MONO (-2140 3535);
FORCEPROP 0 LASTPIN (-2150 3475) $PN BJ65
J 0
(-2140 3485);
DISPLAY 0.489362 (-2140 3485);
PAINT MONO (-2140 3485);
FORCEPROP 0 LASTPIN (-2150 3425) $PN BJ72
J 0
(-2140 3435);
DISPLAY 0.489362 (-2140 3435);
PAINT MONO (-2140 3435);
FORCEPROP 0 LASTPIN (-2150 3375) $PN BK51
J 0
(-2140 3385);
DISPLAY 0.489362 (-2140 3385);
PAINT MONO (-2140 3385);
FORCEPROP 0 LASTPIN (-2150 3325) $PN BK53
J 0
(-2140 3335);
DISPLAY 0.489362 (-2140 3335);
PAINT MONO (-2140 3335);
FORCEPROP 0 LASTPIN (-2150 3275) $PN BL50
J 0
(-2140 3285);
DISPLAY 0.489362 (-2140 3285);
PAINT MONO (-2140 3285);
FORCEPROP 0 LASTPIN (-2150 3225) $PN BL52
J 0
(-2140 3235);
DISPLAY 0.489362 (-2140 3235);
PAINT MONO (-2140 3235);
FORCEPROP 0 LASTPIN (-2150 3175) $PN BL54
J 0
(-2140 3185);
DISPLAY 0.489362 (-2140 3185);
PAINT MONO (-2140 3185);
FORCEPROP 0 LASTPIN (-2150 3125) $PN BM51
J 0
(-2140 3135);
DISPLAY 0.489362 (-2140 3135);
PAINT MONO (-2140 3135);
FORCEPROP 0 LASTPIN (-2150 3075) $PN BM53
J 0
(-2140 3085);
DISPLAY 0.489362 (-2140 3085);
PAINT MONO (-2140 3085);
FORCEPROP 0 LASTPIN (-2150 3025) $PN BM57
J 0
(-2140 3035);
DISPLAY 0.489362 (-2140 3035);
PAINT MONO (-2140 3035);
FORCEPROP 0 LASTPIN (-2150 2975) $PN BM64
J 0
(-2140 2985);
DISPLAY 0.489362 (-2140 2985);
PAINT MONO (-2140 2985);
FORCEPROP 0 LASTPIN (-2150 2925) $PN BM71
J 0
(-2140 2935);
DISPLAY 0.489362 (-2140 2935);
PAINT MONO (-2140 2935);
FORCEPROP 0 LASTPIN (-2150 2875) $PN BN54
J 0
(-2140 2885);
DISPLAY 0.489362 (-2140 2885);
PAINT MONO (-2140 2885);
FORCEPROP 0 LASTPIN (-2150 2825) $PN BR58
J 0
(-2140 2835);
DISPLAY 0.489362 (-2140 2835);
PAINT MONO (-2140 2835);
FORCEPROP 0 LASTPIN (-2150 2775) $PN BR65
J 0
(-2140 2785);
DISPLAY 0.489362 (-2140 2785);
PAINT MONO (-2140 2785);
FORCEPROP 0 LASTPIN (-2150 2725) $PN BR72
J 0
(-2140 2735);
DISPLAY 0.489362 (-2140 2735);
PAINT MONO (-2140 2735);
FORCEPROP 0 LASTPIN (-2150 2675) $PN BV54
J 0
(-2140 2685);
DISPLAY 0.489362 (-2140 2685);
PAINT MONO (-2140 2685);
FORCEPROP 0 LASTPIN (-2150 2625) $PN BV57
J 0
(-2140 2635);
DISPLAY 0.489362 (-2140 2635);
PAINT MONO (-2140 2635);
FORCEPROP 0 LASTPIN (-2150 2575) $PN BV64
J 0
(-2140 2585);
DISPLAY 0.489362 (-2140 2585);
PAINT MONO (-2140 2585);
FORCEPROP 0 LASTPIN (-2150 2525) $PN BV71
J 0
(-2140 2535);
DISPLAY 0.489362 (-2140 2535);
PAINT MONO (-2140 2535);
FORCEPROP 0 LASTPIN (-2150 2475) $PN CA58
J 0
(-2140 2485);
DISPLAY 0.489362 (-2140 2485);
PAINT MONO (-2140 2485);
FORCEPROP 0 LASTPIN (-2150 2425) $PN CA65
J 0
(-2140 2435);
DISPLAY 0.489362 (-2140 2435);
PAINT MONO (-2140 2435);
FORCEPROP 0 LASTPIN (-2150 2375) $PN CA72
J 0
(-2140 2385);
DISPLAY 0.489362 (-2140 2385);
PAINT MONO (-2140 2385);
FORCEPROP 0 LASTPIN (-2150 2325) $PN CB54
J 0
(-2140 2335);
DISPLAY 0.489362 (-2140 2335);
PAINT MONO (-2140 2335);
FORCEPROP 0 LASTPIN (-2150 2275) $PN CD57
J 0
(-2140 2285);
DISPLAY 0.489362 (-2140 2285);
PAINT MONO (-2140 2285);
FORCEPROP 0 LASTPIN (-2150 2225) $PN CD64
J 0
(-2140 2235);
DISPLAY 0.489362 (-2140 2235);
PAINT MONO (-2140 2235);
FORCEPROP 0 LASTPIN (-2150 2175) $PN CD71
J 0
(-2140 2185);
DISPLAY 0.489362 (-2140 2185);
PAINT MONO (-2140 2185);
FORCEPROP 0 LASTPIN (-2150 2125) $PN CF54
J 0
(-2140 2135);
DISPLAY 0.489362 (-2140 2135);
PAINT MONO (-2140 2135);
FORCEPROP 0 LASTPIN (-2150 2075) $PN CG58
J 0
(-2140 2085);
DISPLAY 0.489362 (-2140 2085);
PAINT MONO (-2140 2085);
FORCEPROP 0 LASTPIN (-2150 2025) $PN CG65
J 0
(-2140 2035);
DISPLAY 0.489362 (-2140 2035);
PAINT MONO (-2140 2035);
FORCEPROP 0 LASTPIN (-2150 1975) $PN CG72
J 0
(-2140 1985);
DISPLAY 0.489362 (-2140 1985);
PAINT MONO (-2140 1985);
FORCEPROP 0 LASTPIN (-2150 1925) $PN CJ54
J 0
(-2140 1935);
DISPLAY 0.489362 (-2140 1935);
PAINT MONO (-2140 1935);
FORCEPROP 0 LASTPIN (-2150 1875) $PN CK57
J 0
(-2140 1885);
DISPLAY 0.489362 (-2140 1885);
PAINT MONO (-2140 1885);
FORCEPROP 0 LASTPIN (-2150 1825) $PN CK64
J 0
(-2140 1835);
DISPLAY 0.489362 (-2140 1835);
PAINT MONO (-2140 1835);
FORCEPROP 0 LASTPIN (-2150 1775) $PN CK71
J 0
(-2140 1785);
DISPLAY 0.489362 (-2140 1785);
PAINT MONO (-2140 1785);
FORCEPROP 0 LASTPIN (-2150 1725) $PN CM54
J 0
(-2140 1735);
DISPLAY 0.489362 (-2140 1735);
PAINT MONO (-2140 1735);
FORCEPROP 0 LASTPIN (-2150 1675) $PN CN58
J 0
(-2140 1685);
DISPLAY 0.489362 (-2140 1685);
PAINT MONO (-2140 1685);
FORCEPROP 0 LASTPIN (-2150 1625) $PN CN65
J 0
(-2140 1635);
DISPLAY 0.489362 (-2140 1635);
PAINT MONO (-2140 1635);
FORCEPROP 0 LASTPIN (-2150 1575) $PN CN72
J 0
(-2140 1585);
DISPLAY 0.489362 (-2140 1585);
PAINT MONO (-2140 1585);
FORCEPROP 0 LASTPIN (-2150 1525) $PN CT54
J 0
(-2140 1535);
DISPLAY 0.489362 (-2140 1535);
PAINT MONO (-2140 1535);
FORCEPROP 0 LASTPIN (-2150 1475) $PN CT57
J 0
(-2140 1485);
DISPLAY 0.489362 (-2140 1485);
PAINT MONO (-2140 1485);
FORCEPROP 0 LASTPIN (-2150 1425) $PN CT64
J 0
(-2140 1435);
DISPLAY 0.489362 (-2140 1435);
PAINT MONO (-2140 1435);
FORCEPROP 0 LASTPIN (-2150 1375) $PN CT71
J 0
(-2140 1385);
DISPLAY 0.489362 (-2140 1385);
PAINT MONO (-2140 1385);
FORCEPROP 0 LASTPIN (-2150 1325) $PN CW58
J 0
(-2140 1335);
DISPLAY 0.489362 (-2140 1335);
PAINT MONO (-2140 1335);
FORCEPROP 0 LASTPIN (-2150 1275) $PN CW65
J 0
(-2140 1285);
DISPLAY 0.489362 (-2140 1285);
PAINT MONO (-2140 1285);
FORCEPROP 0 LASTPIN (-2150 1225) $PN CW72
J 0
(-2140 1235);
DISPLAY 0.489362 (-2140 1235);
PAINT MONO (-2140 1235);
FORCEPROP 0 LASTPIN (-2150 1175) $PN CY54
J 0
(-2140 1185);
DISPLAY 0.489362 (-2140 1185);
PAINT MONO (-2140 1185);
FORCEPROP 0 LASTPIN (-2150 1125) $PN DB57
J 0
(-2140 1135);
DISPLAY 0.489362 (-2140 1135);
PAINT MONO (-2140 1135);
FORCEPROP 0 LASTPIN (-2150 1075) $PN DB64
J 0
(-2140 1085);
DISPLAY 0.489362 (-2140 1085);
PAINT MONO (-2140 1085);
FORCEPROP 0 LASTPIN (-2150 1025) $PN DB71
J 0
(-2140 1035);
DISPLAY 0.489362 (-2140 1035);
PAINT MONO (-2140 1035);
FORCEPROP 0 LASTPIN (-2150 975) $PN DE58
J 0
(-2140 985);
DISPLAY 0.489362 (-2140 985);
PAINT MONO (-2140 985);
FORCEPROP 0 LASTPIN (-2150 925) $PN DE65
J 0
(-2140 935);
DISPLAY 0.489362 (-2140 935);
PAINT MONO (-2140 935);
FORCEPROP 0 LASTPIN (-2150 875) $PN DE72
J 0
(-2140 885);
DISPLAY 0.489362 (-2140 885);
PAINT MONO (-2140 885);
FORCEPROP 0 LASTPIN (-2150 825) $PN DG64
J 0
(-2140 835);
DISPLAY 0.489362 (-2140 835);
PAINT MONO (-2140 835);
FORCEPROP 0 LASTPIN (-2150 775) $PN DG71
J 0
(-2140 785);
DISPLAY 0.489362 (-2140 785);
PAINT MONO (-2140 785);
FORCEPROP 0 LASTPIN (-2150 6475) $PN H57
J 0
(-2140 6485);
DISPLAY 0.489362 (-2140 6485);
PAINT MONO (-2140 6485);
FORCEPROP 0 LASTPIN (-2150 6425) $PN H64
J 0
(-2140 6435);
DISPLAY 0.489362 (-2140 6435);
PAINT MONO (-2140 6435);
FORCEPROP 0 LASTPIN (-2150 6375) $PN H71
J 0
(-2140 6385);
DISPLAY 0.489362 (-2140 6385);
PAINT MONO (-2140 6385);
FORCEPROP 0 LASTPIN (-2150 6325) $PN K54
J 0
(-2140 6335);
DISPLAY 0.489362 (-2140 6335);
PAINT MONO (-2140 6335);
FORCEPROP 0 LASTPIN (-2150 6275) $PN L58
J 0
(-2140 6285);
DISPLAY 0.489362 (-2140 6285);
PAINT MONO (-2140 6285);
FORCEPROP 0 LASTPIN (-2150 6225) $PN L65
J 0
(-2140 6235);
DISPLAY 0.489362 (-2140 6235);
PAINT MONO (-2140 6235);
FORCEPROP 0 LASTPIN (-2150 6175) $PN L72
J 0
(-2140 6185);
DISPLAY 0.489362 (-2140 6185);
PAINT MONO (-2140 6185);
FORCEPROP 0 LASTPIN (-2150 6125) $PN P54
J 0
(-2140 6135);
DISPLAY 0.489362 (-2140 6135);
PAINT MONO (-2140 6135);
FORCEPROP 0 LASTPIN (-2150 6075) $PN P57
J 0
(-2140 6085);
DISPLAY 0.489362 (-2140 6085);
PAINT MONO (-2140 6085);
FORCEPROP 0 LASTPIN (-2150 6025) $PN P64
J 0
(-2140 6035);
DISPLAY 0.489362 (-2140 6035);
PAINT MONO (-2140 6035);
FORCEPROP 0 LASTPIN (-2150 5975) $PN P71
J 0
(-2140 5985);
DISPLAY 0.489362 (-2140 5985);
PAINT MONO (-2140 5985);
FORCEPROP 0 LASTPIN (-2150 5925) $PN U58
J 0
(-2140 5935);
DISPLAY 0.489362 (-2140 5935);
PAINT MONO (-2140 5935);
FORCEPROP 0 LASTPIN (-2150 5875) $PN U65
J 0
(-2140 5885);
DISPLAY 0.489362 (-2140 5885);
PAINT MONO (-2140 5885);
FORCEPROP 0 LASTPIN (-2150 5825) $PN U72
J 0
(-2140 5835);
DISPLAY 0.489362 (-2140 5835);
PAINT MONO (-2140 5835);
FORCEPROP 0 LASTPIN (-2150 5775) $PN V54
J 0
(-2140 5785);
DISPLAY 0.489362 (-2140 5785);
PAINT MONO (-2140 5785);
FORCEPROP 0 LASTPIN (-2150 5725) $PN Y57
J 0
(-2140 5735);
DISPLAY 0.489362 (-2140 5735);
PAINT MONO (-2140 5735);
FORCEPROP 0 LASTPIN (-2150 5675) $PN Y64
J 0
(-2140 5685);
DISPLAY 0.489362 (-2140 5685);
PAINT MONO (-2140 5685);
FORCEPROP 0 LASTPIN (-2150 5625) $PN Y71
J 0
(-2140 5635);
DISPLAY 0.489362 (-2140 5635);
PAINT MONO (-2140 5635);
FORCEPROP 1 LAST MATERIAL IO
J 0
(-3295 6607);
DISPLAY 0.489362 (-3295 6607);
PAINT SKYBLUE (-3295 6607);
FORCEPROP 2 LAST PART_TYPE SMLF
J 0
(-3200 6675);
DISPLAY 1.021277 (-3200 6675);
FORCEPROP 1 LAST PART_NUMBER DGA^6000030
J 0
(-3300 6650);
DISPLAY 0.489362 (-3300 6650);
PAINT SKYBLUE (-3300 6650);
FORCEPROP 2 LAST VALUE SOCKET6096_13568-001
J 0
(-3200 6600);
DISPLAY 0.489362 (-3200 6600);
PAINT SKYBLUE (-3200 6600);
FORCEPROP 2 LAST CDS_LIB pure_quanta
J 0
(-2800 3500);
DISPLAY INVISIBLE (-2800 3500);
FORCEPROP 1 LAST CDS_LMAN_SYM_OUTLINE -500,3075,500,-3075
J 0
(-2800 3500);
DISPLAY 0.468085 (-2800 3500);
PAINT GREEN (-2800 3500);
DISPLAY INVISIBLE (-2800 3500);
FORCEPROP 1 LAST NEEDS_NO_SIZE TRUE
J 0
(-2800 3500);
DISPLAY 0.723404 (-2800 3500);
PAINT GREEN (-2800 3500);
DISPLAY INVISIBLE (-2800 3500);
FORCEPROP 1 LAST PATH I45
J 0
(-2800 3500);
DISPLAY 0.723404 (-2800 3500);
PAINT GREEN (-2800 3500);
DISPLAY INVISIBLE (-2800 3500);
FORCEADD GENOA_SP5..23
(-875 4325);
FORCEPROP 1 LAST LOCATION U26
J 0
(-1425 6525);
DISPLAY 0.489362 (-1425 6525);
PAINT SKYBLUE (-1425 6525);
FORCEPROP 0 LAST $SEC 23
J 0
(-1400 6675);
DISPLAY 0.680851 (-1400 6675);
PAINT MONO (-1400 6675);
DISPLAY INVISIBLE (-1400 6675);
FORCEPROP 0 LAST CDS_SEC 23
J 0
(-1400 6675);
DISPLAY 1.021277 (-1400 6675);
DISPLAY INVISIBLE (-1400 6675);
FORCEPROP 0 LASTPIN (-1575 5675) $PN A31
J 2
(-1585 5685);
DISPLAY 0.489362 (-1585 5685);
PAINT MONO (-1585 5685);
FORCEPROP 0 LASTPIN (-1575 5625) $PN A35
J 2
(-1585 5635);
DISPLAY 0.489362 (-1585 5635);
PAINT MONO (-1585 5635);
FORCEPROP 0 LASTPIN (-1575 5575) $PN A41
J 2
(-1585 5585);
DISPLAY 0.489362 (-1585 5585);
PAINT MONO (-1585 5585);
FORCEPROP 0 LASTPIN (-1575 5525) $PN A42
J 2
(-1585 5535);
DISPLAY 0.489362 (-1585 5535);
PAINT MONO (-1585 5535);
FORCEPROP 0 LASTPIN (-1575 5475) $PN A45
J 2
(-1585 5485);
DISPLAY 0.489362 (-1585 5485);
PAINT MONO (-1585 5485);
FORCEPROP 0 LASTPIN (-1575 5425) $PN A48
J 2
(-1585 5435);
DISPLAY 0.489362 (-1585 5435);
PAINT MONO (-1585 5435);
FORCEPROP 0 LASTPIN (-1575 5375) $PN A50
J 2
(-1585 5385);
DISPLAY 0.489362 (-1585 5385);
PAINT MONO (-1585 5385);
FORCEPROP 0 LASTPIN (-1575 5325) $PN A51
J 2
(-1585 5335);
DISPLAY 0.489362 (-1585 5335);
PAINT MONO (-1585 5335);
FORCEPROP 0 LASTPIN (-1575 5275) $PN A54
J 2
(-1585 5285);
DISPLAY 0.489362 (-1585 5285);
PAINT MONO (-1585 5285);
FORCEPROP 0 LASTPIN (-1575 5225) $PN A55
J 2
(-1585 5235);
DISPLAY 0.489362 (-1585 5235);
PAINT MONO (-1585 5235);
FORCEPROP 0 LASTPIN (-1575 5175) $PN A56
J 2
(-1585 5185);
DISPLAY 0.489362 (-1585 5185);
PAINT MONO (-1585 5185);
FORCEPROP 0 LASTPIN (-1575 5125) $PN A57
J 2
(-1585 5135);
DISPLAY 0.489362 (-1585 5135);
PAINT MONO (-1585 5135);
FORCEPROP 0 LASTPIN (-1575 5075) $PN A59
J 2
(-1585 5085);
DISPLAY 0.489362 (-1585 5085);
PAINT MONO (-1585 5085);
FORCEPROP 0 LASTPIN (-1575 5025) $PN A60
J 2
(-1585 5035);
DISPLAY 0.489362 (-1585 5035);
PAINT MONO (-1585 5035);
FORCEPROP 0 LASTPIN (-1575 4975) $PN B40
J 2
(-1585 4985);
DISPLAY 0.489362 (-1585 4985);
PAINT MONO (-1585 4985);
FORCEPROP 0 LASTPIN (-1575 4075) $PN BD4
J 2
(-1585 4085);
DISPLAY 0.489362 (-1585 4085);
PAINT MONO (-1585 4085);
FORCEPROP 0 LASTPIN (-1575 4025) $PN BD7
J 2
(-1585 4035);
DISPLAY 0.489362 (-1585 4035);
PAINT MONO (-1585 4035);
FORCEPROP 0 LASTPIN (-1575 3975) $PN BD11
J 2
(-1585 3985);
DISPLAY 0.489362 (-1585 3985);
PAINT MONO (-1585 3985);
FORCEPROP 0 LASTPIN (-1575 3925) $PN BD14
J 2
(-1585 3935);
DISPLAY 0.489362 (-1585 3935);
PAINT MONO (-1585 3935);
FORCEPROP 0 LASTPIN (-1575 3875) $PN BD18
J 2
(-1585 3885);
DISPLAY 0.489362 (-1585 3885);
PAINT MONO (-1585 3885);
FORCEPROP 0 LASTPIN (-1575 3825) $PN BD21
J 2
(-1585 3835);
DISPLAY 0.489362 (-1585 3835);
PAINT MONO (-1585 3835);
FORCEPROP 0 LASTPIN (-1575 3775) $PN BD55
J 2
(-1585 3785);
DISPLAY 0.489362 (-1585 3785);
PAINT MONO (-1585 3785);
FORCEPROP 0 LASTPIN (-1575 3725) $PN BD58
J 2
(-1585 3735);
DISPLAY 0.489362 (-1585 3735);
PAINT MONO (-1585 3735);
FORCEPROP 0 LASTPIN (-1575 3675) $PN BD62
J 2
(-1585 3685);
DISPLAY 0.489362 (-1585 3685);
PAINT MONO (-1585 3685);
FORCEPROP 0 LASTPIN (-1575 3625) $PN BD65
J 2
(-1585 3635);
DISPLAY 0.489362 (-1585 3635);
PAINT MONO (-1585 3635);
FORCEPROP 0 LASTPIN (-1575 3575) $PN BD69
J 2
(-1585 3585);
DISPLAY 0.489362 (-1585 3585);
PAINT MONO (-1585 3585);
FORCEPROP 0 LASTPIN (-1575 3525) $PN BD72
J 2
(-1585 3535);
DISPLAY 0.489362 (-1585 3535);
PAINT MONO (-1585 3535);
FORCEPROP 0 LASTPIN (-1575 4925) $PN C31
J 2
(-1585 4935);
DISPLAY 0.489362 (-1585 4935);
PAINT MONO (-1585 4935);
FORCEPROP 0 LASTPIN (-1575 4875) $PN C34
J 2
(-1585 4885);
DISPLAY 0.489362 (-1585 4885);
PAINT MONO (-1585 4885);
FORCEPROP 0 LASTPIN (-1575 4825) $PN C35
J 2
(-1585 4835);
DISPLAY 0.489362 (-1585 4835);
PAINT MONO (-1585 4835);
FORCEPROP 0 LASTPIN (-1575 4775) $PN C53
J 2
(-1585 4785);
DISPLAY 0.489362 (-1585 4785);
PAINT MONO (-1585 4785);
FORCEPROP 0 LASTPIN (-1575 4725) $PN C54
J 2
(-1585 4735);
DISPLAY 0.489362 (-1585 4735);
PAINT MONO (-1585 4735);
FORCEPROP 0 LASTPIN (-1575 4675) $PN D4
J 2
(-1585 4685);
DISPLAY 0.489362 (-1585 4685);
PAINT MONO (-1585 4685);
FORCEPROP 0 LASTPIN (-1575 4625) $PN D8
J 2
(-1585 4635);
DISPLAY 0.489362 (-1585 4635);
PAINT MONO (-1585 4635);
FORCEPROP 0 LASTPIN (-1575 4575) $PN D11
J 2
(-1585 4585);
DISPLAY 0.489362 (-1585 4585);
PAINT MONO (-1585 4585);
FORCEPROP 0 LASTPIN (-1575 4525) $PN D22
J 2
(-1585 4535);
DISPLAY 0.489362 (-1585 4535);
PAINT MONO (-1585 4535);
FORCEPROP 0 LASTPIN (-1575 4475) $PN D34
J 2
(-1585 4485);
DISPLAY 0.489362 (-1585 4485);
PAINT MONO (-1585 4485);
FORCEPROP 0 LASTPIN (-1575 4425) $PN D36
J 2
(-1585 4435);
DISPLAY 0.489362 (-1585 4435);
PAINT MONO (-1585 4435);
FORCEPROP 0 LASTPIN (-1575 4375) $PN D58
J 2
(-1585 4385);
DISPLAY 0.489362 (-1585 4385);
PAINT MONO (-1585 4385);
FORCEPROP 0 LASTPIN (-1575 4325) $PN D62
J 2
(-1585 4335);
DISPLAY 0.489362 (-1585 4335);
PAINT MONO (-1585 4335);
FORCEPROP 0 LASTPIN (-1575 4275) $PN D65
J 2
(-1585 4285);
DISPLAY 0.489362 (-1585 4285);
PAINT MONO (-1585 4285);
FORCEPROP 0 LASTPIN (-1575 4225) $PN D72
J 2
(-1585 4235);
DISPLAY 0.489362 (-1585 4235);
PAINT MONO (-1585 4235);
FORCEPROP 0 LASTPIN (-1575 3475) $PN DG17
J 2
(-1585 3485);
DISPLAY 0.489362 (-1585 3485);
PAINT MONO (-1585 3485);
FORCEPROP 0 LASTPIN (-1575 3425) $PN DH17
J 2
(-1585 3435);
DISPLAY 0.489362 (-1585 3435);
PAINT MONO (-1585 3435);
FORCEPROP 0 LASTPIN (-1575 3375) $PN DH21
J 2
(-1585 3385);
DISPLAY 0.489362 (-1585 3385);
PAINT MONO (-1585 3385);
FORCEPROP 0 LASTPIN (-1575 3325) $PN DJ4
J 2
(-1585 3335);
DISPLAY 0.489362 (-1585 3335);
PAINT MONO (-1585 3335);
FORCEPROP 0 LASTPIN (-1575 4175) $PN E33
J 2
(-1585 4185);
DISPLAY 0.489362 (-1585 4185);
PAINT MONO (-1585 4185);
FORCEPROP 0 LASTPIN (-1575 4125) $PN E36
J 2
(-1585 4135);
DISPLAY 0.489362 (-1585 4135);
PAINT MONO (-1585 4135);
FORCEPROP 0 LASTPIN (-1575 3125) $PN C58
J 2
(-1585 3135);
DISPLAY 0.489362 (-1585 3135);
PAINT MONO (-1585 3135);
FORCEPROP 0 LASTPIN (-1575 2875) $PN DH13
J 2
(-1585 2885);
DISPLAY 0.489362 (-1585 2885);
PAINT MONO (-1585 2885);
FORCEPROP 0 LASTPIN (-1575 2975) $PN DF41
J 2
(-1585 2985);
DISPLAY 0.489362 (-1585 2985);
PAINT MONO (-1585 2985);
FORCEPROP 0 LASTPIN (-1575 3175) $PN C23
J 2
(-1585 3185);
DISPLAY 0.489362 (-1585 3185);
PAINT MONO (-1585 3185);
FORCEPROP 0 LASTPIN (-1575 3075) $PN C59
J 2
(-1585 3085);
DISPLAY 0.489362 (-1585 3085);
PAINT MONO (-1585 3085);
FORCEPROP 0 LASTPIN (-1575 2825) $PN DH14
J 2
(-1585 2835);
DISPLAY 0.489362 (-1585 2835);
PAINT MONO (-1585 2835);
FORCEPROP 0 LASTPIN (-1575 2925) $PN DG42
J 2
(-1585 2935);
DISPLAY 0.489362 (-1585 2935);
PAINT MONO (-1585 2935);
FORCEPROP 0 LASTPIN (-1575 3025) $PN D23
J 2
(-1585 3035);
DISPLAY 0.489362 (-1585 3035);
PAINT MONO (-1585 3035);
FORCEPROP 0 LASTPIN (-1575 2675) $PN B36
J 2
(-1585 2685);
DISPLAY 0.489362 (-1585 2685);
PAINT MONO (-1585 2685);
FORCEPROP 0 LASTPIN (-1575 2775) $PN DJ57
J 2
(-1585 2785);
DISPLAY 0.489362 (-1585 2785);
PAINT MONO (-1585 2785);
FORCEPROP 2 LAST PART_TYPE SMLF
J 0
(-1425 6450);
DISPLAY 1.021277 (-1425 6450);
FORCEPROP 1 LAST PART_NUMBER DGA^6000030
J 0
(-1425 6400);
DISPLAY 0.489362 (-1425 6400);
PAINT SKYBLUE (-1425 6400);
FORCEPROP 1 LAST MATERIAL IO
J 0
(-1420 6357);
DISPLAY 0.489362 (-1420 6357);
PAINT SKYBLUE (-1420 6357);
FORCEPROP 2 LAST VALUE SOCKET6096_13568-001
J 0
(-1325 6350);
DISPLAY 0.489362 (-1325 6350);
PAINT SKYBLUE (-1325 6350);
FORCEPROP 2 LAST CDS_LIB pure_quanta
J 0
(-875 4325);
DISPLAY INVISIBLE (-875 4325);
FORCEPROP 1 LAST CDS_LMAN_SYM_OUTLINE -550,2000,550,-2000
J 0
(-875 4325);
DISPLAY 0.468085 (-875 4325);
PAINT GREEN (-875 4325);
DISPLAY INVISIBLE (-875 4325);
FORCEPROP 1 LAST NEEDS_NO_SIZE TRUE
J 0
(-875 4325);
DISPLAY 0.723404 (-875 4325);
PAINT GREEN (-875 4325);
DISPLAY INVISIBLE (-875 4325);
FORCEPROP 1 LAST PATH I46
J 0
(-875 4325);
DISPLAY 0.723404 (-875 4325);
PAINT GREEN (-875 4325);
DISPLAY INVISIBLE (-875 4325);
FORCEADD VCC_CORE..1
(-3825 6250);
FORCEPROP 3 LASTPIN (-3825 6200) SIG_NAME PVDDCR_SOC_P1\g
J 0
(-3815 6210);
DISPLAY 0.659574 (-3815 6210);
PAINT MONO (-3815 6210);
DISPLAY INVISIBLE (-3815 6210);
FORCEPROP 1 LAST HDL_POWER PVDDCR_SOC_P1
J 1
(-3825 6300);
DISPLAY 0.489362 (-3825 6300);
PAINT GREEN (-3825 6300);
FORCEPROP 2 LAST CDS_LIB pure_quanta_power
J 0
(-3825 6250);
DISPLAY INVISIBLE (-3825 6250);
FORCEPROP 1 LAST PATH I47
J 0
(-3775 6275);
DISPLAY 0.872340 (-3775 6275);
PAINT AQUA (-3775 6275);
DISPLAY INVISIBLE (-3775 6275);
FORCEADD VCC_CORE..1
(-5125 6250);
FORCEPROP 3 LASTPIN (-5125 6200) SIG_NAME PVDDCR_SOC_P1\g
J 0
(-5115 6210);
DISPLAY 0.659574 (-5115 6210);
PAINT MONO (-5115 6210);
DISPLAY INVISIBLE (-5115 6210);
FORCEPROP 1 LAST HDL_POWER PVDDCR_SOC_P1
J 1
(-5125 6300);
DISPLAY 0.489362 (-5125 6300);
PAINT GREEN (-5125 6300);
FORCEPROP 2 LAST CDS_LIB pure_quanta_power
J 0
(-5125 6250);
DISPLAY INVISIBLE (-5125 6250);
FORCEPROP 1 LAST PATH I48
J 0
(-5075 6275);
DISPLAY 0.872340 (-5075 6275);
PAINT AQUA (-5075 6275);
DISPLAY INVISIBLE (-5075 6275);
FORCEADD GENOA_SP5..26
(-4475 4675);
FORCEPROP 1 LAST LOCATION U26
J 0
(-4925 6575);
DISPLAY 0.489362 (-4925 6575);
PAINT SKYBLUE (-4925 6575);
FORCEPROP 0 LAST $SEC 26
J 0
(-4900 6675);
DISPLAY 0.680851 (-4900 6675);
PAINT MONO (-4900 6675);
DISPLAY INVISIBLE (-4900 6675);
FORCEPROP 0 LAST CDS_SEC 26
J 0
(-4900 6675);
DISPLAY 1.021277 (-4900 6675);
DISPLAY INVISIBLE (-4900 6675);
FORCEPROP 0 LASTPIN (-5075 5025) $PN AA22
J 2
(-5085 5035);
DISPLAY 0.489362 (-5085 5035);
PAINT MONO (-5085 5035);
FORCEPROP 0 LASTPIN (-5075 4975) $PN AC4
J 2
(-5085 4985);
DISPLAY 0.489362 (-5085 4985);
PAINT MONO (-5085 4985);
FORCEPROP 0 LASTPIN (-5075 4925) $PN AC11
J 2
(-5085 4935);
DISPLAY 0.489362 (-5085 4935);
PAINT MONO (-5085 4935);
FORCEPROP 0 LASTPIN (-5075 4875) $PN AC18
J 2
(-5085 4885);
DISPLAY 0.489362 (-5085 4885);
PAINT MONO (-5085 4885);
FORCEPROP 0 LASTPIN (-5075 4825) $PN AD22
J 2
(-5085 4835);
DISPLAY 0.489362 (-5085 4835);
PAINT MONO (-5085 4835);
FORCEPROP 0 LASTPIN (-5075 4775) $PN AF5
J 2
(-5085 4785);
DISPLAY 0.489362 (-5085 4785);
PAINT MONO (-5085 4785);
FORCEPROP 0 LASTPIN (-5075 4725) $PN AF12
J 2
(-5085 4735);
DISPLAY 0.489362 (-5085 4735);
PAINT MONO (-5085 4735);
FORCEPROP 0 LASTPIN (-5075 4675) $PN AF19
J 2
(-5085 4685);
DISPLAY 0.489362 (-5085 4685);
PAINT MONO (-5085 4685);
FORCEPROP 0 LASTPIN (-5075 4625) $PN AH22
J 2
(-5085 4635);
DISPLAY 0.489362 (-5085 4635);
PAINT MONO (-5085 4635);
FORCEPROP 0 LASTPIN (-5075 4575) $PN AJ4
J 2
(-5085 4585);
DISPLAY 0.489362 (-5085 4585);
PAINT MONO (-5085 4585);
FORCEPROP 0 LASTPIN (-5075 4525) $PN AJ11
J 2
(-5085 4535);
DISPLAY 0.489362 (-5085 4535);
PAINT MONO (-5085 4535);
FORCEPROP 0 LASTPIN (-5075 4475) $PN AJ18
J 2
(-5085 4485);
DISPLAY 0.489362 (-5085 4485);
PAINT MONO (-5085 4485);
FORCEPROP 0 LASTPIN (-5075 4425) $PN AM5
J 2
(-5085 4435);
DISPLAY 0.489362 (-5085 4435);
PAINT MONO (-5085 4435);
FORCEPROP 0 LASTPIN (-5075 4375) $PN AM12
J 2
(-5085 4385);
DISPLAY 0.489362 (-5085 4385);
PAINT MONO (-5085 4385);
FORCEPROP 0 LASTPIN (-5075 4325) $PN AM19
J 2
(-5085 4335);
DISPLAY 0.489362 (-5085 4335);
PAINT MONO (-5085 4335);
FORCEPROP 0 LASTPIN (-5075 4275) $PN AM22
J 2
(-5085 4285);
DISPLAY 0.489362 (-5085 4285);
PAINT MONO (-5085 4285);
FORCEPROP 0 LASTPIN (-5075 4225) $PN AR4
J 2
(-5085 4235);
DISPLAY 0.489362 (-5085 4235);
PAINT MONO (-5085 4235);
FORCEPROP 0 LASTPIN (-5075 4175) $PN AR11
J 2
(-5085 4185);
DISPLAY 0.489362 (-5085 4185);
PAINT MONO (-5085 4185);
FORCEPROP 0 LASTPIN (-5075 4125) $PN AR18
J 2
(-5085 4135);
DISPLAY 0.489362 (-5085 4135);
PAINT MONO (-5085 4135);
FORCEPROP 0 LASTPIN (-5075 4075) $PN AT22
J 2
(-5085 4085);
DISPLAY 0.489362 (-5085 4085);
PAINT MONO (-5085 4085);
FORCEPROP 0 LASTPIN (-5075 4025) $PN AU23
J 2
(-5085 4035);
DISPLAY 0.489362 (-5085 4035);
PAINT MONO (-5085 4035);
FORCEPROP 0 LASTPIN (-5075 3975) $PN AU27
J 2
(-5085 3985);
DISPLAY 0.489362 (-5085 3985);
PAINT MONO (-5085 3985);
FORCEPROP 0 LASTPIN (-5075 3925) $PN AU31
J 2
(-5085 3935);
DISPLAY 0.489362 (-5085 3935);
PAINT MONO (-5085 3935);
FORCEPROP 0 LASTPIN (-5075 3875) $PN AU35
J 2
(-5085 3885);
DISPLAY 0.489362 (-5085 3885);
PAINT MONO (-5085 3885);
FORCEPROP 0 LASTPIN (-5075 3825) $PN AU40
J 2
(-5085 3835);
DISPLAY 0.489362 (-5085 3835);
PAINT MONO (-5085 3835);
FORCEPROP 0 LASTPIN (-5075 3775) $PN AV5
J 2
(-5085 3785);
DISPLAY 0.489362 (-5085 3785);
PAINT MONO (-5085 3785);
FORCEPROP 0 LASTPIN (-5075 3725) $PN AV12
J 2
(-5085 3735);
DISPLAY 0.489362 (-5085 3735);
PAINT MONO (-5085 3735);
FORCEPROP 0 LASTPIN (-5075 3675) $PN AV19
J 2
(-5085 3685);
DISPLAY 0.489362 (-5085 3685);
PAINT MONO (-5085 3685);
FORCEPROP 0 LASTPIN (-5075 3625) $PN AV22
J 2
(-5085 3635);
DISPLAY 0.489362 (-5085 3635);
PAINT MONO (-5085 3635);
FORCEPROP 0 LASTPIN (-5075 3575) $PN AV24
J 2
(-5085 3585);
DISPLAY 0.489362 (-5085 3585);
PAINT MONO (-5085 3585);
FORCEPROP 0 LASTPIN (-5075 3525) $PN AV26
J 2
(-5085 3535);
DISPLAY 0.489362 (-5085 3535);
PAINT MONO (-5085 3535);
FORCEPROP 0 LASTPIN (-5075 3475) $PN AV28
J 2
(-5085 3485);
DISPLAY 0.489362 (-5085 3485);
PAINT MONO (-5085 3485);
FORCEPROP 0 LASTPIN (-5075 3425) $PN AV30
J 2
(-5085 3435);
DISPLAY 0.489362 (-5085 3435);
PAINT MONO (-5085 3435);
FORCEPROP 0 LASTPIN (-5075 3375) $PN AV32
J 2
(-5085 3385);
DISPLAY 0.489362 (-5085 3385);
PAINT MONO (-5085 3385);
FORCEPROP 0 LASTPIN (-5075 3325) $PN AV34
J 2
(-5085 3335);
DISPLAY 0.489362 (-5085 3335);
PAINT MONO (-5085 3335);
FORCEPROP 0 LASTPIN (-5075 3275) $PN AV36
J 2
(-5085 3285);
DISPLAY 0.489362 (-5085 3285);
PAINT MONO (-5085 3285);
FORCEPROP 0 LASTPIN (-5075 3225) $PN AV39
J 2
(-5085 3235);
DISPLAY 0.489362 (-5085 3235);
PAINT MONO (-5085 3235);
FORCEPROP 0 LASTPIN (-5075 3175) $PN AV41
J 2
(-5085 3185);
DISPLAY 0.489362 (-5085 3185);
PAINT MONO (-5085 3185);
FORCEPROP 0 LASTPIN (-3875 6125) $PN AV43
J 0
(-3865 6135);
DISPLAY 0.489362 (-3865 6135);
PAINT MONO (-3865 6135);
FORCEPROP 0 LASTPIN (-3875 6075) $PN AV45
J 0
(-3865 6085);
DISPLAY 0.489362 (-3865 6085);
PAINT MONO (-3865 6085);
FORCEPROP 0 LASTPIN (-3875 6025) $PN AV47
J 0
(-3865 6035);
DISPLAY 0.489362 (-3865 6035);
PAINT MONO (-3865 6035);
FORCEPROP 0 LASTPIN (-3875 5975) $PN AW23
J 0
(-3865 5985);
DISPLAY 0.489362 (-3865 5985);
PAINT MONO (-3865 5985);
FORCEPROP 0 LASTPIN (-3875 5925) $PN AW25
J 0
(-3865 5935);
DISPLAY 0.489362 (-3865 5935);
PAINT MONO (-3865 5935);
FORCEPROP 0 LASTPIN (-3875 5875) $PN AW27
J 0
(-3865 5885);
DISPLAY 0.489362 (-3865 5885);
PAINT MONO (-3865 5885);
FORCEPROP 0 LASTPIN (-3875 5825) $PN AW48
J 0
(-3865 5835);
DISPLAY 0.489362 (-3865 5835);
PAINT MONO (-3865 5835);
FORCEPROP 0 LASTPIN (-3875 5775) $PN AY22
J 0
(-3865 5785);
DISPLAY 0.489362 (-3865 5785);
PAINT MONO (-3865 5785);
FORCEPROP 0 LASTPIN (-3875 5725) $PN AY24
J 0
(-3865 5735);
DISPLAY 0.489362 (-3865 5735);
PAINT MONO (-3865 5735);
FORCEPROP 0 LASTPIN (-3875 5675) $PN AY26
J 0
(-3865 5685);
DISPLAY 0.489362 (-3865 5685);
PAINT MONO (-3865 5685);
FORCEPROP 0 LASTPIN (-3875 5625) $PN AY28
J 0
(-3865 5635);
DISPLAY 0.489362 (-3865 5635);
PAINT MONO (-3865 5635);
FORCEPROP 0 LASTPIN (-3875 5575) $PN AY49
J 0
(-3865 5585);
DISPLAY 0.489362 (-3865 5585);
PAINT MONO (-3865 5585);
FORCEPROP 0 LASTPIN (-5075 6125) $PN B5
J 2
(-5085 6135);
DISPLAY 0.489362 (-5085 6135);
PAINT MONO (-5085 6135);
FORCEPROP 0 LASTPIN (-3875 5525) $PN BA4
J 0
(-3865 5535);
DISPLAY 0.489362 (-3865 5535);
PAINT MONO (-3865 5535);
FORCEPROP 0 LASTPIN (-3875 5475) $PN BA11
J 0
(-3865 5485);
DISPLAY 0.489362 (-3865 5485);
PAINT MONO (-3865 5485);
FORCEPROP 0 LASTPIN (-3875 5425) $PN BA18
J 0
(-3865 5435);
DISPLAY 0.489362 (-3865 5435);
PAINT MONO (-3865 5435);
FORCEPROP 0 LASTPIN (-3875 5375) $PN BA23
J 0
(-3865 5385);
DISPLAY 0.489362 (-3865 5385);
PAINT MONO (-3865 5385);
FORCEPROP 0 LASTPIN (-3875 5325) $PN BA25
J 0
(-3865 5335);
DISPLAY 0.489362 (-3865 5335);
PAINT MONO (-3865 5335);
FORCEPROP 0 LASTPIN (-3875 5275) $PN BA27
J 0
(-3865 5285);
DISPLAY 0.489362 (-3865 5285);
PAINT MONO (-3865 5285);
FORCEPROP 0 LASTPIN (-3875 5225) $PN BA48
J 0
(-3865 5235);
DISPLAY 0.489362 (-3865 5235);
PAINT MONO (-3865 5235);
FORCEPROP 0 LASTPIN (-3875 5175) $PN BB22
J 0
(-3865 5185);
DISPLAY 0.489362 (-3865 5185);
PAINT MONO (-3865 5185);
FORCEPROP 0 LASTPIN (-3875 5125) $PN BB24
J 0
(-3865 5135);
DISPLAY 0.489362 (-3865 5135);
PAINT MONO (-3865 5135);
FORCEPROP 0 LASTPIN (-3875 5075) $PN BB26
J 0
(-3865 5085);
DISPLAY 0.489362 (-3865 5085);
PAINT MONO (-3865 5085);
FORCEPROP 0 LASTPIN (-3875 5025) $PN BB28
J 0
(-3865 5035);
DISPLAY 0.489362 (-3865 5035);
PAINT MONO (-3865 5035);
FORCEPROP 0 LASTPIN (-3875 4975) $PN BB49
J 0
(-3865 4985);
DISPLAY 0.489362 (-3865 4985);
PAINT MONO (-3865 4985);
FORCEPROP 0 LASTPIN (-3875 4925) $PN BC23
J 0
(-3865 4935);
DISPLAY 0.489362 (-3865 4935);
PAINT MONO (-3865 4935);
FORCEPROP 0 LASTPIN (-3875 4875) $PN BC25
J 0
(-3865 4885);
DISPLAY 0.489362 (-3865 4885);
PAINT MONO (-3865 4885);
FORCEPROP 0 LASTPIN (-3875 4825) $PN BC27
J 0
(-3865 4835);
DISPLAY 0.489362 (-3865 4835);
PAINT MONO (-3865 4835);
FORCEPROP 0 LASTPIN (-3875 4775) $PN BC48
J 0
(-3865 4785);
DISPLAY 0.489362 (-3865 4785);
PAINT MONO (-3865 4785);
FORCEPROP 0 LASTPIN (-3875 4725) $PN BD5
J 0
(-3865 4735);
DISPLAY 0.489362 (-3865 4735);
PAINT MONO (-3865 4735);
FORCEPROP 0 LASTPIN (-3875 4675) $PN BD12
J 0
(-3865 4685);
DISPLAY 0.489362 (-3865 4685);
PAINT MONO (-3865 4685);
FORCEPROP 0 LASTPIN (-3875 4625) $PN BD19
J 0
(-3865 4635);
DISPLAY 0.489362 (-3865 4635);
PAINT MONO (-3865 4635);
FORCEPROP 0 LASTPIN (-3875 4575) $PN BD22
J 0
(-3865 4585);
DISPLAY 0.489362 (-3865 4585);
PAINT MONO (-3865 4585);
FORCEPROP 0 LASTPIN (-3875 4525) $PN BD24
J 0
(-3865 4535);
DISPLAY 0.489362 (-3865 4535);
PAINT MONO (-3865 4535);
FORCEPROP 0 LASTPIN (-3875 4475) $PN BD26
J 0
(-3865 4485);
DISPLAY 0.489362 (-3865 4485);
PAINT MONO (-3865 4485);
FORCEPROP 0 LASTPIN (-3875 4425) $PN BD28
J 0
(-3865 4435);
DISPLAY 0.489362 (-3865 4435);
PAINT MONO (-3865 4435);
FORCEPROP 0 LASTPIN (-3875 4375) $PN BD48
J 0
(-3865 4385);
DISPLAY 0.489362 (-3865 4385);
PAINT MONO (-3865 4385);
FORCEPROP 0 LASTPIN (-3875 4325) $PN BF23
J 0
(-3865 4335);
DISPLAY 0.489362 (-3865 4335);
PAINT MONO (-3865 4335);
FORCEPROP 0 LASTPIN (-3875 4275) $PN BF25
J 0
(-3865 4285);
DISPLAY 0.489362 (-3865 4285);
PAINT MONO (-3865 4285);
FORCEPROP 0 LASTPIN (-3875 4225) $PN BF27
J 0
(-3865 4235);
DISPLAY 0.489362 (-3865 4235);
PAINT MONO (-3865 4235);
FORCEPROP 0 LASTPIN (-3875 4175) $PN BF48
J 0
(-3865 4185);
DISPLAY 0.489362 (-3865 4185);
PAINT MONO (-3865 4185);
FORCEPROP 0 LASTPIN (-3875 4125) $PN BG22
J 0
(-3865 4135);
DISPLAY 0.489362 (-3865 4135);
PAINT MONO (-3865 4135);
FORCEPROP 0 LASTPIN (-3875 4075) $PN BG24
J 0
(-3865 4085);
DISPLAY 0.489362 (-3865 4085);
PAINT MONO (-3865 4085);
FORCEPROP 0 LASTPIN (-3875 4025) $PN BG26
J 0
(-3865 4035);
DISPLAY 0.489362 (-3865 4035);
PAINT MONO (-3865 4035);
FORCEPROP 0 LASTPIN (-3875 3975) $PN BG28
J 0
(-3865 3985);
DISPLAY 0.489362 (-3865 3985);
PAINT MONO (-3865 3985);
FORCEPROP 0 LASTPIN (-3875 3925) $PN BG48
J 0
(-3865 3935);
DISPLAY 0.489362 (-3865 3935);
PAINT MONO (-3865 3935);
FORCEPROP 0 LASTPIN (-3875 3875) $PN BH23
J 0
(-3865 3885);
DISPLAY 0.489362 (-3865 3885);
PAINT MONO (-3865 3885);
FORCEPROP 0 LASTPIN (-3875 3825) $PN BH25
J 0
(-3865 3835);
DISPLAY 0.489362 (-3865 3835);
PAINT MONO (-3865 3835);
FORCEPROP 0 LASTPIN (-3875 3775) $PN BH48
J 0
(-3865 3785);
DISPLAY 0.489362 (-3865 3785);
PAINT MONO (-3865 3785);
FORCEPROP 0 LASTPIN (-3875 3725) $PN BJ4
J 0
(-3865 3735);
DISPLAY 0.489362 (-3865 3735);
PAINT MONO (-3865 3735);
FORCEPROP 0 LASTPIN (-3875 3675) $PN BJ11
J 0
(-3865 3685);
DISPLAY 0.489362 (-3865 3685);
PAINT MONO (-3865 3685);
FORCEPROP 0 LASTPIN (-3875 3625) $PN BJ48
J 0
(-3865 3635);
DISPLAY 0.489362 (-3865 3635);
PAINT MONO (-3865 3635);
FORCEPROP 0 LASTPIN (-3875 3575) $PN BM5
J 0
(-3865 3585);
DISPLAY 0.489362 (-3865 3585);
PAINT MONO (-3865 3585);
FORCEPROP 0 LASTPIN (-5075 6075) $PN C4
J 2
(-5085 6085);
DISPLAY 0.489362 (-5085 6085);
PAINT MONO (-5085 6085);
FORCEPROP 0 LASTPIN (-5075 6025) $PN E4
J 2
(-5085 6035);
DISPLAY 0.489362 (-5085 6035);
PAINT MONO (-5085 6035);
FORCEPROP 0 LASTPIN (-5075 5975) $PN E11
J 2
(-5085 5985);
DISPLAY 0.489362 (-5085 5985);
PAINT MONO (-5085 5985);
FORCEPROP 0 LASTPIN (-5075 5925) $PN H5
J 2
(-5085 5935);
DISPLAY 0.489362 (-5085 5935);
PAINT MONO (-5085 5935);
FORCEPROP 0 LASTPIN (-5075 5875) $PN H12
J 2
(-5085 5885);
DISPLAY 0.489362 (-5085 5885);
PAINT MONO (-5085 5885);
FORCEPROP 0 LASTPIN (-5075 5825) $PN H19
J 2
(-5085 5835);
DISPLAY 0.489362 (-5085 5835);
PAINT MONO (-5085 5835);
FORCEPROP 0 LASTPIN (-5075 5775) $PN K22
J 2
(-5085 5785);
DISPLAY 0.489362 (-5085 5785);
PAINT MONO (-5085 5785);
FORCEPROP 0 LASTPIN (-5075 5725) $PN L4
J 2
(-5085 5735);
DISPLAY 0.489362 (-5085 5735);
PAINT MONO (-5085 5735);
FORCEPROP 0 LASTPIN (-5075 5675) $PN L11
J 2
(-5085 5685);
DISPLAY 0.489362 (-5085 5685);
PAINT MONO (-5085 5685);
FORCEPROP 0 LASTPIN (-5075 5625) $PN L18
J 2
(-5085 5635);
DISPLAY 0.489362 (-5085 5635);
PAINT MONO (-5085 5635);
FORCEPROP 0 LASTPIN (-5075 5575) $PN P5
J 2
(-5085 5585);
DISPLAY 0.489362 (-5085 5585);
PAINT MONO (-5085 5585);
FORCEPROP 0 LASTPIN (-5075 5525) $PN P12
J 2
(-5085 5535);
DISPLAY 0.489362 (-5085 5535);
PAINT MONO (-5085 5535);
FORCEPROP 0 LASTPIN (-5075 5475) $PN P19
J 2
(-5085 5485);
DISPLAY 0.489362 (-5085 5485);
PAINT MONO (-5085 5485);
FORCEPROP 0 LASTPIN (-5075 5425) $PN P22
J 2
(-5085 5435);
DISPLAY 0.489362 (-5085 5435);
PAINT MONO (-5085 5435);
FORCEPROP 0 LASTPIN (-5075 5375) $PN U4
J 2
(-5085 5385);
DISPLAY 0.489362 (-5085 5385);
PAINT MONO (-5085 5385);
FORCEPROP 0 LASTPIN (-5075 5325) $PN U11
J 2
(-5085 5335);
DISPLAY 0.489362 (-5085 5335);
PAINT MONO (-5085 5335);
FORCEPROP 0 LASTPIN (-5075 5275) $PN U18
J 2
(-5085 5285);
DISPLAY 0.489362 (-5085 5285);
PAINT MONO (-5085 5285);
FORCEPROP 0 LASTPIN (-5075 5225) $PN V22
J 2
(-5085 5235);
DISPLAY 0.489362 (-5085 5235);
PAINT MONO (-5085 5235);
FORCEPROP 0 LASTPIN (-5075 5175) $PN Y5
J 2
(-5085 5185);
DISPLAY 0.489362 (-5085 5185);
PAINT MONO (-5085 5185);
FORCEPROP 0 LASTPIN (-5075 5125) $PN Y12
J 2
(-5085 5135);
DISPLAY 0.489362 (-5085 5135);
PAINT MONO (-5085 5135);
FORCEPROP 0 LASTPIN (-5075 5075) $PN Y19
J 2
(-5085 5085);
DISPLAY 0.489362 (-5085 5085);
PAINT MONO (-5085 5085);
FORCEPROP 2 LAST PART_TYPE SMLF
J 0
(-4925 6525);
DISPLAY 1.021277 (-4925 6525);
FORCEPROP 1 LAST MATERIAL IO
J 0
(-4920 6357);
DISPLAY 0.489362 (-4920 6357);
PAINT SKYBLUE (-4920 6357);
FORCEPROP 1 LAST PART_NUMBER DGA^6000030
J 0
(-4920 6484);
DISPLAY 0.489362 (-4920 6484);
PAINT SKYBLUE (-4920 6484);
FORCEPROP 2 LAST VALUE SOCKET6096_13568-001
J 0
(-4925 6425);
DISPLAY 0.489362 (-4925 6425);
PAINT SKYBLUE (-4925 6425);
FORCEPROP 2 LAST CDS_LIB pure_quanta
J 0
(-4475 4675);
DISPLAY INVISIBLE (-4475 4675);
FORCEPROP 1 LAST CDS_LMAN_SYM_OUTLINE -450,1650,450,-1650
J 0
(-4475 4675);
DISPLAY 0.468085 (-4475 4675);
PAINT GREEN (-4475 4675);
DISPLAY INVISIBLE (-4475 4675);
FORCEPROP 1 LAST NEEDS_NO_SIZE TRUE
J 0
(-4475 4675);
DISPLAY 0.723404 (-4475 4675);
PAINT GREEN (-4475 4675);
DISPLAY INVISIBLE (-4475 4675);
FORCEPROP 1 LAST PATH I49
J 0
(-4475 4675);
DISPLAY 0.723404 (-4475 4675);
PAINT GREEN (-4475 4675);
DISPLAY INVISIBLE (-4475 4675);
FORCEADD Q_RES..2
(-1125 725);
FORCEPROP 1 LAST LOCATION R374
J 0
(-1075 800);
DISPLAY 0.489362 (-1075 800);
PAINT SKYBLUE (-1075 800);
FORCEPROP 0 LAST $SEC 1
J 0
(-1075 850);
DISPLAY 0.680851 (-1075 850);
PAINT MONO (-1075 850);
DISPLAY INVISIBLE (-1075 850);
FORCEPROP 0 LAST CDS_SEC 1
J 0
(-1075 850);
DISPLAY 1.021277 (-1075 850);
DISPLAY INVISIBLE (-1075 850);
FORCEPROP 1 LASTPIN (-1125 825) $PN 1
J 0
(-1120 787);
DISPLAY 0.489362 (-1120 787);
PAINT MONO (-1120 787);
FORCEPROP 1 LASTPIN (-1125 625) $PN 2
J 0
(-1120 635);
DISPLAY 0.489362 (-1120 635);
PAINT MONO (-1120 635);
FORCEPROP 1 LAST WATTAGE 1/16W
J 0
(-1075 725);
DISPLAY 0.489362 (-1075 725);
PAINT SKYBLUE (-1075 725);
FORCEPROP 1 LAST MATERIAL CHIP
J 0
(-1075 700);
DISPLAY 0.489362 (-1075 700);
PAINT SKYBLUE (-1075 700);
FORCEPROP 1 LAST TOLERANCE 5%
J 0
(-1075 750);
DISPLAY 0.489362 (-1075 750);
PAINT SKYBLUE (-1075 750);
FORCEPROP 1 LAST VALUE 0
J 0
(-1075 775);
DISPLAY 0.489362 (-1075 775);
PAINT SKYBLUE (-1075 775);
FORCEPROP 1 LAST PACK_TYPE 0402LF
J 0
(-1075 675);
DISPLAY 0.489362 (-1075 675);
PAINT SKYBLUE (-1075 675);
FORCEPROP 2 LAST BOM_COST MEM
R 3
J 0
(-1250 650);
DISPLAY 0.574468 (-1250 650);
PAINT WHITE (-1250 650);
DISPLAY INVISIBLE (-1250 650);
FORCEPROP 2 LAST CDS_LIB pure_quanta
J 0
(-1125 725);
DISPLAY INVISIBLE (-1125 725);
FORCEPROP 1 LAST PATH I51
J 0
(-1075 900);
DISPLAY 0.978723 (-1075 900);
PAINT WHITE (-1075 900);
DISPLAY INVISIBLE (-1075 900);
FORCEPROP 1 LAST PART_NUMBER CS00002JB38
J 0
(-1075 675);
DISPLAY 0.489362 (-1075 675);
PAINT SKYBLUE (-1075 675);
DISPLAY INVISIBLE (-1075 675);
FORCEPROP 2 LAST ROOM RST_CPU1_PLD_TO_DIMM
R 3
J 0
(-1300 600);
DISPLAY 0.574468 (-1300 600);
PAINT RED (-1300 600);
DISPLAY INVISIBLE (-1300 600);
FORCEADD Q_RES..2
(-1450 725);
FORCEPROP 1 LAST LOCATION R373
J 0
(-1425 800);
DISPLAY 0.489362 (-1425 800);
PAINT SKYBLUE (-1425 800);
FORCEPROP 0 LAST $SEC 1
J 0
(-1425 850);
DISPLAY 0.680851 (-1425 850);
PAINT MONO (-1425 850);
DISPLAY INVISIBLE (-1425 850);
FORCEPROP 0 LAST CDS_SEC 1
J 0
(-1425 850);
DISPLAY 1.021277 (-1425 850);
DISPLAY INVISIBLE (-1425 850);
FORCEPROP 1 LASTPIN (-1450 825) $PN 1
J 0
(-1445 787);
DISPLAY 0.489362 (-1445 787);
PAINT MONO (-1445 787);
FORCEPROP 1 LASTPIN (-1450 625) $PN 2
J 0
(-1445 635);
DISPLAY 0.489362 (-1445 635);
PAINT MONO (-1445 635);
FORCEPROP 1 LAST WATTAGE 1/16W
J 0
(-1400 725);
DISPLAY 0.489362 (-1400 725);
PAINT SKYBLUE (-1400 725);
FORCEPROP 1 LAST MATERIAL EMPTY
J 0
(-1400 700);
DISPLAY 0.489362 (-1400 700);
PAINT RED (-1400 700);
FORCEPROP 1 LAST TOLERANCE 5%
J 0
(-1400 750);
DISPLAY 0.489362 (-1400 750);
PAINT SKYBLUE (-1400 750);
FORCEPROP 1 LAST VALUE 0
J 0
(-1400 775);
DISPLAY 0.489362 (-1400 775);
PAINT SKYBLUE (-1400 775);
FORCEPROP 1 LAST PART_NUMBER CS00002JB38
J 0
(-1400 675);
DISPLAY 0.489362 (-1400 675);
PAINT SKYBLUE (-1400 675);
FORCEPROP 1 LAST PACK_TYPE 0402LF
J 0
(-1400 650);
DISPLAY 0.489362 (-1400 650);
PAINT SKYBLUE (-1400 650);
FORCEPROP 2 LAST BOM_COST MEM
R 3
J 0
(-1575 650);
DISPLAY 0.574468 (-1575 650);
PAINT WHITE (-1575 650);
DISPLAY INVISIBLE (-1575 650);
FORCEPROP 2 LAST CDS_LIB pure_quanta
J 0
(-1450 725);
DISPLAY INVISIBLE (-1450 725);
FORCEPROP 1 LAST PATH I52
J 0
(-1400 900);
DISPLAY 0.978723 (-1400 900);
PAINT WHITE (-1400 900);
DISPLAY INVISIBLE (-1400 900);
FORCEPROP 2 LAST ROOM RST_CPU1_PLD_TO_DIMM
R 3
J 0
(-1625 600);
DISPLAY 0.574468 (-1625 600);
PAINT RED (-1625 600);
DISPLAY INVISIBLE (-1625 600);
FORCEADD QUANTA_TITLE_BLOCK_C..1
(-100 100);
FORCEPROP 0 LAST CDS_CON_LAST_MODIFIED Fri Mar 11 14:52:39 2022
J 0
(-1985 115);
DISPLAY INVISIBLE (-1985 115);
FORCEPROP 1 LAST CUSTOM_TXT_CDS <CON_LAST_MODIFIED>
J 0
(-1985 115);
DISPLAY 0.978723 (-1985 115);
FORCEPROP 2 LAST CUSTOM_TXT_CDS <XR_PAGE_TITLE>
J 0
(-7990 5350);
DISPLAY 0.638298 (-7990 5350);
PAINT PINK (-7990 5350);
DISPLAY INVISIBLE (-7990 5350);
FORCEPROP 1 LAST CUSTOM_TXT_CDS <NAME_2>
J 0
(-3275 150);
FORCEPROP 1 LAST CUSTOM_TXT_CDS <NAME_1>
J 0
(-3275 275);
FORCEPROP 1 LAST CUSTOM_TXT_CDS <Q_NUMBER>
J 0
(-1503 203);
DISPLAY 1.212766 (-1503 203);
FORCEPROP 1 LAST CUSTOM_TXT_CDS <Q_PROJ>
J 0
(-2482 202);
DISPLAY 1.212766 (-2482 202);
FORCEPROP 1 LAST CUSTOM_TXT_CDS <Q_REV>
J 0
(-284 203);
DISPLAY 1.212766 (-284 203);
FORCEPROP 1 LAST CUSTOM_TXT_CDS <CON_PAGE_NUM> OF <CON_TOTAL_PAGES>
J 0
(-546 118);
DISPLAY 0.978723 (-546 118);
FORCEPROP 1 LAST Q_TITLE CPU1 POWER
J 0
(-9400 150);
DISPLAY 1.574468 (-9400 150);
PAINT GREEN (-9400 150);
FORCEPROP 1 LAST Q_DEPT BU9
J 1
(-3863 149);
DISPLAY 1.957447 (-3863 149);
PAINT GREEN (-3863 149);
FORCEPROP 2 LAST PAGE_BORDER TRUE
J 0
(-7990 5350);
DISPLAY 0.638298 (-7990 5350);
PAINT PINK (-7990 5350);
DISPLAY INVISIBLE (-7990 5350);
FORCEPROP 1 LAST CDS_LMAN_SYM_OUTLINE -9475,6775,100,-125
J 0
(-100 100);
DISPLAY 0.468085 (-100 100);
PAINT GREEN (-100 100);
DISPLAY INVISIBLE (-100 100);
FORCEPROP 2 LAST CDS_LIB pure_quanta
J 0
(-100 100);
DISPLAY INVISIBLE (-100 100);
FORCEPROP 1 LAST COMMENT_BODY TRUE
J 0
(-88 87);
DISPLAY 0.978723 (-88 87);
PAINT GREEN (-88 87);
DISPLAY INVISIBLE (-88 87);
FORCEPROP 2 LAST CDS_XR_PAGE_TITLE CR-57 : @T6G_MB_LIB.T6G(SCH_1):PAGE57
J 0
(-7990 5350);
DISPLAY 0.638298 (-7990 5350);
PAINT PINK (-7990 5350);
DISPLAY INVISIBLE (-7990 5350);
FORCEADD DNS..2
(-1425 725);
PAINT RED (-1425 725);
FORCEPROP 2 LAST CDS_LIB mstr_misc
J 0
(-1425 725);
DISPLAY INVISIBLE (-1425 725);
FORCEPROP 1 LAST COMMENT_BODY TRUE
R 1
J 0
(-1350 500);
DISPLAY 0.872340 (-1350 500);
PAINT GREEN (-1350 500);
DISPLAY INVISIBLE (-1350 500);
WIRE 16 -1 (-1125 825)(-1125 900);
WIRE 16 -1 (-1450 825)(-1450 900);
WIRE 16 -1 (-2050 825)(-2050 775);
WIRE 16 -1 (-2050 875)(-2050 825);
WIRE 16 -1 (-2050 825)(-2150 825);
WIRE 16 -1 (-2050 775)(-2150 775);
WIRE 16 -1 (-2050 925)(-2050 875);
WIRE 16 -1 (-2050 875)(-2150 875);
WIRE 16 -1 (-2050 925)(-2150 925);
WIRE 16 -1 (-2050 975)(-2050 925);
WIRE 16 -1 (-2050 1025)(-2050 975);
WIRE 16 -1 (-2150 975)(-2050 975);
WIRE 16 -1 (-2050 1075)(-2050 1025);
WIRE 16 -1 (-2050 1025)(-2150 1025);
WIRE 16 -1 (-2150 1075)(-2050 1075);
WIRE 16 -1 (-2050 1125)(-2050 1075);
WIRE 16 -1 (-2050 1175)(-2050 1125);
WIRE 16 -1 (-2050 1125)(-2150 1125);
WIRE 16 -1 (-2050 1225)(-2050 1175);
WIRE 16 -1 (-2050 1175)(-2150 1175);
WIRE 16 -1 (-2150 1225)(-2050 1225);
WIRE 16 -1 (-2050 1275)(-2050 1225);
WIRE 16 -1 (-2050 1325)(-2050 1275);
WIRE 16 -1 (-2050 1275)(-2150 1275);
WIRE 16 -1 (-2050 1325)(-2150 1325);
WIRE 16 -1 (-2050 1375)(-2050 1325);
WIRE 16 -1 (-2050 1425)(-2050 1375);
WIRE 16 -1 (-2050 1375)(-2150 1375);
WIRE 16 -1 (-2050 1475)(-2050 1425);
WIRE 16 -1 (-2050 1425)(-2150 1425);
WIRE 16 -1 (-2050 1525)(-2050 1475);
WIRE 16 -1 (-2050 1475)(-2150 1475);
WIRE 16 -1 (-2150 1525)(-2050 1525);
WIRE 16 -1 (-2050 1575)(-2050 1525);
WIRE 16 -1 (-2050 1575)(-2150 1575);
WIRE 16 -1 (-2050 1625)(-2050 1575);
WIRE 16 -1 (-2050 1675)(-2050 1625);
WIRE 16 -1 (-2050 1625)(-2150 1625);
WIRE 16 -1 (-2050 1725)(-2050 1675);
WIRE 16 -1 (-2050 1675)(-2150 1675);
WIRE 16 -1 (-2050 1775)(-2050 1725);
WIRE 16 -1 (-2050 1725)(-2150 1725);
WIRE 16 -1 (-2150 1775)(-2050 1775);
WIRE 16 -1 (-2050 1825)(-2050 1775);
WIRE 16 -1 (-2050 1825)(-2150 1825);
WIRE 16 -1 (-2050 1875)(-2050 1825);
WIRE 16 -1 (-2050 1925)(-2050 1875);
WIRE 16 -1 (-2150 1875)(-2050 1875);
WIRE 16 -1 (-2050 1975)(-2050 1925);
WIRE 16 -1 (-2050 1925)(-2150 1925);
WIRE 16 -1 (-2050 2025)(-2050 1975);
WIRE 16 -1 (-2050 1975)(-2150 1975);
WIRE 16 -1 (-2150 2025)(-2050 2025);
WIRE 16 -1 (-2050 2075)(-2050 2025);
WIRE 16 -1 (-2050 2125)(-2050 2075);
WIRE 16 -1 (-2050 2075)(-2150 2075);
WIRE 16 -1 (-2050 2175)(-2050 2125);
WIRE 16 -1 (-2050 2125)(-2150 2125);
WIRE 16 -1 (-2050 2225)(-2050 2175);
WIRE 16 -1 (-2050 2175)(-2150 2175);
WIRE 16 -1 (-2050 2225)(-2150 2225);
WIRE 16 -1 (-2050 2275)(-2050 2225);
WIRE 16 -1 (-2050 2325)(-2050 2275);
WIRE 16 -1 (-2050 2275)(-2150 2275);
WIRE 16 -1 (-2050 2375)(-2050 2325);
WIRE 16 -1 (-2150 2325)(-2050 2325);
WIRE 16 -1 (-2050 2425)(-2050 2375);
WIRE 16 -1 (-2050 2375)(-2150 2375);
WIRE 16 -1 (-2050 2475)(-2050 2425);
WIRE 16 -1 (-2050 2425)(-2150 2425);
WIRE 16 -1 (-2050 2475)(-2150 2475);
WIRE 16 -1 (-2050 2525)(-2050 2475);
WIRE 16 -1 (-2050 2575)(-2050 2525);
WIRE 16 -1 (-2050 2525)(-2150 2525);
WIRE 16 -1 (-2050 2625)(-2050 2575);
WIRE 16 -1 (-2150 2575)(-2050 2575);
WIRE 16 -1 (-2050 2675)(-2050 2625);
WIRE 16 -1 (-2050 2625)(-2150 2625);
WIRE 16 -1 (-2150 2675)(-2050 2675);
WIRE 16 -1 (-2050 2725)(-2050 2675);
WIRE 16 -1 (-2050 2725)(-2150 2725);
WIRE 16 -1 (-2050 2775)(-2050 2725);
WIRE 16 -1 (-2050 2825)(-2050 2775);
WIRE 16 -1 (-2050 2775)(-2150 2775);
WIRE 16 -1 (-2050 2875)(-2050 2825);
WIRE 16 -1 (-2150 2825)(-2050 2825);
WIRE 16 -1 (-2050 2925)(-2050 2875);
WIRE 16 -1 (-2050 2875)(-2150 2875);
WIRE 16 -1 (-2050 2975)(-2050 2925);
WIRE 16 -1 (-2050 2925)(-2150 2925);
WIRE 16 -1 (-2050 2975)(-2150 2975);
WIRE 16 -1 (-2050 3025)(-2050 2975);
WIRE 16 -1 (-2050 3075)(-2050 3025);
WIRE 16 -1 (-2050 3025)(-2150 3025);
WIRE 16 -1 (-2050 3125)(-2050 3075);
WIRE 16 -1 (-2050 3075)(-2150 3075);
WIRE 16 -1 (-2150 3125)(-2050 3125);
WIRE 16 -1 (-2050 3175)(-2050 3125);
WIRE 16 -1 (-2050 3225)(-2050 3175);
WIRE 16 -1 (-2050 3175)(-2150 3175);
WIRE 16 -1 (-2050 3275)(-2050 3225);
WIRE 16 -1 (-2050 3225)(-2150 3225);
WIRE 16 -1 (-2050 3325)(-2050 3275);
WIRE 16 -1 (-2050 3275)(-2150 3275);
WIRE 16 -1 (-2050 3375)(-2050 3325);
WIRE 16 -1 (-2050 3325)(-2150 3325);
WIRE 16 -1 (-2150 3375)(-2050 3375);
WIRE 16 -1 (-2050 3425)(-2050 3375);
WIRE 16 -1 (-2050 3475)(-2050 3425);
WIRE 16 -1 (-2050 3425)(-2150 3425);
WIRE 16 -1 (-2050 3525)(-2050 3475);
WIRE 16 -1 (-2150 3475)(-2050 3475);
WIRE 16 -1 (-2050 3575)(-2050 3525);
WIRE 16 -1 (-2050 3525)(-2150 3525);
WIRE 16 -1 (-2050 3625)(-2050 3575);
WIRE 16 -1 (-2050 3575)(-2150 3575);
WIRE 16 -1 (-2150 3625)(-2050 3625);
WIRE 16 -1 (-2050 3675)(-2050 3625);
WIRE 16 -1 (-2050 3725)(-2050 3675);
WIRE 16 -1 (-2050 3675)(-2150 3675);
WIRE 16 -1 (-2050 3775)(-2050 3725);
WIRE 16 -1 (-2050 3725)(-2150 3725);
WIRE 16 -1 (-2050 3825)(-2050 3775);
WIRE 16 -1 (-2050 3775)(-2150 3775);
WIRE 16 -1 (-2050 3875)(-2050 3825);
WIRE 16 -1 (-2050 3825)(-2150 3825);
WIRE 16 -1 (-2050 3875)(-2150 3875);
WIRE 16 -1 (-2050 3925)(-2050 3875);
WIRE 16 -1 (-2050 3975)(-2050 3925);
WIRE 16 -1 (-2150 3925)(-2050 3925);
WIRE 16 -1 (-2050 4025)(-2050 3975);
WIRE 16 -1 (-2050 3975)(-2150 3975);
WIRE 16 -1 (-2050 4075)(-2050 4025);
WIRE 16 -1 (-2050 4025)(-2150 4025);
WIRE 16 -1 (-2050 4125)(-2050 4075);
WIRE 16 -1 (-2050 4075)(-2150 4075);
WIRE 16 -1 (-2050 4125)(-2150 4125);
WIRE 16 -1 (-2050 4175)(-2050 4125);
WIRE 16 -1 (-2050 4225)(-2050 4175);
WIRE 16 -1 (-2150 4175)(-2050 4175);
WIRE 16 -1 (-2050 4275)(-2050 4225);
WIRE 16 -1 (-2050 4225)(-2150 4225);
WIRE 16 -1 (-2150 4275)(-2050 4275);
WIRE 16 -1 (-2050 4325)(-2050 4275);
WIRE 16 -1 (-2050 4375)(-2050 4325);
WIRE 16 -1 (-2050 4325)(-2150 4325);
WIRE 16 -1 (-2050 4425)(-2050 4375);
WIRE 16 -1 (-2050 4375)(-2150 4375);
WIRE 16 -1 (-2150 4425)(-2050 4425);
WIRE 16 -1 (-2050 4475)(-2050 4425);
WIRE 16 -1 (-2050 4525)(-2050 4475);
WIRE 16 -1 (-2050 4475)(-2150 4475);
WIRE 16 -1 (-2050 4525)(-2150 4525);
WIRE 16 -1 (-2050 4575)(-2050 4525);
WIRE 16 -1 (-2050 4625)(-2050 4575);
WIRE 16 -1 (-2050 4575)(-2150 4575);
WIRE 16 -1 (-2050 4675)(-2050 4625);
WIRE 16 -1 (-2050 4625)(-2150 4625);
WIRE 16 -1 (-2150 4675)(-2050 4675);
WIRE 16 -1 (-2050 4725)(-2050 4675);
WIRE 16 -1 (-2050 4775)(-2050 4725);
WIRE 16 -1 (-2050 4725)(-2150 4725);
WIRE 16 -1 (-2050 4775)(-2150 4775);
WIRE 16 -1 (-2050 4825)(-2050 4775);
WIRE 16 -1 (-2050 4875)(-2050 4825);
WIRE 16 -1 (-2050 4825)(-2150 4825);
WIRE 16 -1 (-2050 4925)(-2050 4875);
WIRE 16 -1 (-2050 4875)(-2150 4875);
WIRE 16 -1 (-2150 4925)(-2050 4925);
WIRE 16 -1 (-2050 4975)(-2050 4925);
WIRE 16 -1 (-2050 5025)(-2050 4975);
WIRE 16 -1 (-2050 4975)(-2150 4975);
WIRE 16 -1 (-2050 5025)(-2150 5025);
WIRE 16 -1 (-2050 5075)(-2050 5025);
WIRE 16 -1 (-2050 5125)(-2050 5075);
WIRE 16 -1 (-2050 5075)(-2150 5075);
WIRE 16 -1 (-2050 5175)(-2050 5125);
WIRE 16 -1 (-2050 5125)(-2150 5125);
WIRE 16 -1 (-2150 5175)(-2050 5175);
WIRE 16 -1 (-2050 5225)(-2050 5175);
WIRE 16 -1 (-2050 5275)(-2050 5225);
WIRE 16 -1 (-2050 5225)(-2150 5225);
WIRE 16 -1 (-2050 5325)(-2050 5275);
WIRE 16 -1 (-2050 5275)(-2150 5275);
WIRE 16 -1 (-2050 5375)(-2050 5325);
WIRE 16 -1 (-2050 5325)(-2150 5325);
WIRE 16 -1 (-2050 5425)(-2050 5375);
WIRE 16 -1 (-2050 5375)(-2150 5375);
WIRE 16 -1 (-2150 5425)(-2050 5425);
WIRE 16 -1 (-2050 5475)(-2050 5425);
WIRE 16 -1 (-2050 5525)(-2050 5475);
WIRE 16 -1 (-2050 5475)(-2150 5475);
WIRE 16 -1 (-2050 5575)(-2050 5525);
WIRE 16 -1 (-2050 5525)(-2150 5525);
WIRE 16 -1 (-2050 5625)(-2050 5575);
WIRE 16 -1 (-2050 5575)(-2150 5575);
WIRE 16 -1 (-2050 5675)(-2050 5625);
WIRE 16 -1 (-2050 5625)(-2150 5625);
WIRE 16 -1 (-2050 5725)(-2050 5675);
WIRE 16 -1 (-2150 5675)(-2050 5675);
WIRE 16 -1 (-2050 5775)(-2050 5725);
WIRE 16 -1 (-2050 5725)(-2150 5725);
WIRE 16 -1 (-2050 5825)(-2050 5775);
WIRE 16 -1 (-2050 5775)(-2150 5775);
WIRE 16 -1 (-2050 5875)(-2050 5825);
WIRE 16 -1 (-2050 5825)(-2150 5825);
WIRE 16 -1 (-2050 5925)(-2050 5875);
WIRE 16 -1 (-2050 5875)(-2150 5875);
WIRE 16 -1 (-2050 5975)(-2050 5925);
WIRE 16 -1 (-2150 5925)(-2050 5925);
WIRE 16 -1 (-2050 6025)(-2050 5975);
WIRE 16 -1 (-2050 5975)(-2150 5975);
WIRE 16 -1 (-2050 6075)(-2050 6025);
WIRE 16 -1 (-2050 6025)(-2150 6025);
WIRE 16 -1 (-2050 6125)(-2050 6075);
WIRE 16 -1 (-2050 6075)(-2150 6075);
WIRE 16 -1 (-2050 6175)(-2050 6125);
WIRE 16 -1 (-2050 6125)(-2150 6125);
WIRE 16 -1 (-2050 6225)(-2050 6175);
WIRE 16 -1 (-2150 6175)(-2050 6175);
WIRE 16 -1 (-2050 6275)(-2050 6225);
WIRE 16 -1 (-2050 6225)(-2150 6225);
WIRE 16 -1 (-2050 6325)(-2050 6275);
WIRE 16 -1 (-2050 6275)(-2150 6275);
WIRE 16 -1 (-2050 6375)(-2050 6325);
WIRE 16 -1 (-2050 6325)(-2150 6325);
WIRE 16 -1 (-2050 6425)(-2050 6375);
WIRE 16 -1 (-2050 6375)(-2150 6375);
WIRE 16 -1 (-2050 6475)(-2050 6425);
WIRE 16 -1 (-2150 6425)(-2050 6425);
WIRE 16 -1 (-2150 6475)(-2050 6475);
WIRE 16 -1 (-2050 6525)(-2050 6475);
WIRE 16 -1 (-8875 600)(-8800 600);
WIRE 16 -1 (-8875 650)(-8875 600);
WIRE 16 -1 (-8875 650)(-8800 650);
WIRE 16 -1 (-8875 700)(-8875 650);
WIRE 16 -1 (-8875 700)(-8800 700);
WIRE 16 -1 (-8875 750)(-8875 700);
WIRE 16 -1 (-8875 800)(-8875 750);
WIRE 16 -1 (-8875 750)(-8800 750);
WIRE 16 -1 (-8875 800)(-8800 800);
WIRE 16 -1 (-8875 850)(-8875 800);
WIRE 16 -1 (-8875 850)(-8800 850);
WIRE 16 -1 (-8875 900)(-8875 850);
WIRE 16 -1 (-8875 900)(-8800 900);
WIRE 16 -1 (-8875 950)(-8875 900);
WIRE 16 -1 (-8875 950)(-8800 950);
WIRE 16 -1 (-8875 1000)(-8875 950);
WIRE 16 -1 (-8875 1050)(-8875 1000);
WIRE 16 -1 (-8875 1000)(-8800 1000);
WIRE 16 -1 (-8875 1050)(-8800 1050);
WIRE 16 -1 (-8875 1100)(-8875 1050);
WIRE 16 -1 (-8875 1100)(-8800 1100);
WIRE 16 -1 (-8875 1150)(-8875 1100);
WIRE 16 -1 (-8875 1150)(-8800 1150);
WIRE 16 -1 (-8875 1200)(-8875 1150);
WIRE 16 -1 (-8875 1200)(-8800 1200);
WIRE 16 -1 (-8875 1250)(-8875 1200);
WIRE 16 -1 (-8875 1300)(-8875 1250);
WIRE 16 -1 (-8875 1250)(-8800 1250);
WIRE 16 -1 (-8875 1300)(-8800 1300);
WIRE 16 -1 (-8875 1350)(-8875 1300);
WIRE 16 -1 (-8875 1350)(-8800 1350);
WIRE 16 -1 (-8875 1400)(-8875 1350);
WIRE 16 -1 (-8875 1400)(-8800 1400);
WIRE 16 -1 (-8875 1450)(-8875 1400);
WIRE 16 -1 (-8875 1450)(-8800 1450);
WIRE 16 -1 (-8875 1500)(-8875 1450);
WIRE 16 -1 (-8875 1550)(-8875 1500);
WIRE 16 -1 (-8875 1500)(-8800 1500);
WIRE 16 -1 (-8875 1550)(-8800 1550);
WIRE 16 -1 (-8875 1600)(-8875 1550);
WIRE 16 -1 (-8875 1600)(-8800 1600);
WIRE 16 -1 (-8875 1650)(-8875 1600);
WIRE 16 -1 (-8875 1650)(-8800 1650);
WIRE 16 -1 (-8875 1700)(-8875 1650);
WIRE 16 -1 (-8875 1700)(-8800 1700);
WIRE 16 -1 (-8875 1750)(-8875 1700);
WIRE 16 -1 (-8875 1800)(-8875 1750);
WIRE 16 -1 (-8875 1750)(-8800 1750);
WIRE 16 -1 (-8875 1800)(-8800 1800);
WIRE 16 -1 (-8875 1850)(-8875 1800);
WIRE 16 -1 (-8875 1850)(-8800 1850);
WIRE 16 -1 (-8875 1900)(-8875 1850);
WIRE 16 -1 (-8875 1900)(-8800 1900);
WIRE 16 -1 (-8875 1950)(-8875 1900);
WIRE 16 -1 (-8875 1950)(-8800 1950);
WIRE 16 -1 (-8875 2000)(-8875 1950);
WIRE 16 -1 (-8875 2050)(-8875 2000);
WIRE 16 -1 (-8875 2000)(-8800 2000);
WIRE 16 -1 (-8875 2050)(-8800 2050);
WIRE 16 -1 (-8875 2100)(-8875 2050);
WIRE 16 -1 (-8875 2100)(-8800 2100);
WIRE 16 -1 (-8875 2150)(-8875 2100);
WIRE 16 -1 (-8875 2150)(-8800 2150);
WIRE 16 -1 (-8875 2200)(-8875 2150);
WIRE 16 -1 (-8875 2200)(-8800 2200);
WIRE 16 -1 (-8875 2250)(-8875 2200);
WIRE 16 -1 (-8875 2250)(-8800 2250);
WIRE 16 -1 (-8875 2300)(-8875 2250);
WIRE 16 -1 (-8875 2350)(-8875 2300);
WIRE 16 -1 (-8875 2300)(-8800 2300);
WIRE 16 -1 (-8875 2350)(-8800 2350);
WIRE 16 -1 (-8875 2400)(-8875 2350);
WIRE 16 -1 (-8875 2400)(-8800 2400);
WIRE 16 -1 (-8875 2450)(-8875 2400);
WIRE 16 -1 (-8875 2450)(-8800 2450);
WIRE 16 -1 (-8875 2500)(-8875 2450);
WIRE 16 -1 (-8875 2500)(-8800 2500);
WIRE 16 -1 (-8875 2550)(-8875 2500);
WIRE 16 -1 (-8875 2600)(-8875 2550);
WIRE 16 -1 (-8875 2550)(-8800 2550);
WIRE 16 -1 (-8875 2600)(-8800 2600);
WIRE 16 -1 (-8875 2650)(-8875 2600);
WIRE 16 -1 (-8875 2650)(-8800 2650);
WIRE 16 -1 (-8875 2700)(-8875 2650);
WIRE 16 -1 (-8875 2700)(-8800 2700);
WIRE 16 -1 (-8875 2750)(-8875 2700);
WIRE 16 -1 (-8875 2750)(-8800 2750);
WIRE 16 -1 (-8875 2800)(-8875 2750);
WIRE 16 -1 (-8875 2850)(-8875 2800);
WIRE 16 -1 (-8875 2800)(-8800 2800);
WIRE 16 -1 (-8875 2850)(-8800 2850);
WIRE 16 -1 (-8875 2900)(-8875 2850);
WIRE 16 -1 (-8875 2900)(-8800 2900);
WIRE 16 -1 (-8875 2950)(-8875 2900);
WIRE 16 -1 (-8875 2950)(-8800 2950);
WIRE 16 -1 (-8875 3000)(-8875 2950);
WIRE 16 -1 (-8875 3000)(-8800 3000);
WIRE 16 -1 (-8875 3050)(-8875 3000);
WIRE 16 -1 (-8875 3100)(-8875 3050);
WIRE 16 -1 (-8875 3050)(-8800 3050);
WIRE 16 -1 (-8875 3100)(-8800 3100);
WIRE 16 -1 (-8875 3150)(-8875 3100);
WIRE 16 -1 (-8875 3150)(-8800 3150);
WIRE 16 -1 (-8875 3200)(-8875 3150);
WIRE 16 -1 (-8875 3200)(-8800 3200);
WIRE 16 -1 (-8875 3250)(-8875 3200);
WIRE 16 -1 (-8875 3250)(-8800 3250);
WIRE 16 -1 (-8875 3300)(-8875 3250);
WIRE 16 -1 (-8875 3350)(-8875 3300);
WIRE 16 -1 (-8875 3300)(-8800 3300);
WIRE 16 -1 (-8875 3350)(-8800 3350);
WIRE 16 -1 (-8875 3400)(-8875 3350);
WIRE 16 -1 (-8875 3400)(-8800 3400);
WIRE 16 -1 (-8875 3450)(-8875 3400);
WIRE 16 -1 (-8875 3450)(-8800 3450);
WIRE 16 -1 (-8875 3500)(-8875 3450);
WIRE 16 -1 (-8875 3500)(-8800 3500);
WIRE 16 -1 (-8875 3550)(-8875 3500);
WIRE 16 -1 (-8875 3600)(-8875 3550);
WIRE 16 -1 (-8875 3550)(-8800 3550);
WIRE 16 -1 (-8875 3600)(-8800 3600);
WIRE 16 -1 (-8875 3650)(-8875 3600);
WIRE 16 -1 (-8875 3650)(-8800 3650);
WIRE 16 -1 (-8875 3700)(-8875 3650);
WIRE 16 -1 (-8875 3700)(-8800 3700);
WIRE 16 -1 (-8875 3750)(-8875 3700);
WIRE 16 -1 (-8875 3750)(-8800 3750);
WIRE 16 -1 (-8875 3800)(-8875 3750);
WIRE 16 -1 (-8875 3850)(-8875 3800);
WIRE 16 -1 (-8875 3800)(-8800 3800);
WIRE 16 -1 (-8875 3850)(-8800 3850);
WIRE 16 -1 (-8875 3900)(-8875 3850);
WIRE 16 -1 (-8875 3900)(-8800 3900);
WIRE 16 -1 (-8875 3950)(-8875 3900);
WIRE 16 -1 (-8875 3950)(-8800 3950);
WIRE 16 -1 (-8875 4000)(-8875 3950);
WIRE 16 -1 (-8875 4000)(-8800 4000);
WIRE 16 -1 (-8875 4050)(-8875 4000);
WIRE 16 -1 (-8875 4100)(-8875 4050);
WIRE 16 -1 (-8875 4050)(-8800 4050);
WIRE 16 -1 (-8875 4100)(-8800 4100);
WIRE 16 -1 (-8875 4150)(-8875 4100);
WIRE 16 -1 (-8875 4150)(-8800 4150);
WIRE 16 -1 (-8875 4200)(-8875 4150);
WIRE 16 -1 (-8875 4200)(-8800 4200);
WIRE 16 -1 (-8875 4250)(-8875 4200);
WIRE 16 -1 (-8875 4250)(-8800 4250);
WIRE 16 -1 (-8875 4300)(-8875 4250);
WIRE 16 -1 (-8875 4300)(-8800 4300);
WIRE 16 -1 (-8875 4350)(-8875 4300);
WIRE 16 -1 (-8875 4400)(-8875 4350);
WIRE 16 -1 (-8875 4350)(-8800 4350);
WIRE 16 -1 (-8875 4400)(-8800 4400);
WIRE 16 -1 (-8875 4450)(-8875 4400);
WIRE 16 -1 (-8875 4450)(-8800 4450);
WIRE 16 -1 (-8875 4500)(-8875 4450);
WIRE 16 -1 (-8875 4500)(-8800 4500);
WIRE 16 -1 (-8875 4550)(-8875 4500);
WIRE 16 -1 (-8875 4550)(-8800 4550);
WIRE 16 -1 (-8875 4600)(-8875 4550);
WIRE 16 -1 (-8875 4650)(-8875 4600);
WIRE 16 -1 (-8875 4600)(-8800 4600);
WIRE 16 -1 (-8875 4650)(-8800 4650);
WIRE 16 -1 (-8875 4700)(-8875 4650);
WIRE 16 -1 (-8875 4700)(-8800 4700);
WIRE 16 -1 (-8875 4750)(-8875 4700);
WIRE 16 -1 (-8875 4750)(-8800 4750);
WIRE 16 -1 (-8875 4800)(-8875 4750);
WIRE 16 -1 (-8875 4800)(-8800 4800);
WIRE 16 -1 (-8875 4850)(-8875 4800);
WIRE 16 -1 (-8875 4900)(-8875 4850);
WIRE 16 -1 (-8875 4850)(-8800 4850);
WIRE 16 -1 (-8875 4900)(-8800 4900);
WIRE 16 -1 (-8875 4950)(-8875 4900);
WIRE 16 -1 (-8875 4950)(-8800 4950);
WIRE 16 -1 (-8875 5000)(-8875 4950);
WIRE 16 -1 (-8875 5000)(-8800 5000);
WIRE 16 -1 (-8875 5050)(-8875 5000);
WIRE 16 -1 (-8875 5050)(-8800 5050);
WIRE 16 -1 (-8875 5100)(-8875 5050);
WIRE 16 -1 (-8875 5150)(-8875 5100);
WIRE 16 -1 (-8875 5100)(-8800 5100);
WIRE 16 -1 (-8875 5150)(-8800 5150);
WIRE 16 -1 (-8875 5200)(-8875 5150);
WIRE 16 -1 (-8875 5200)(-8800 5200);
WIRE 16 -1 (-8875 5250)(-8875 5200);
WIRE 16 -1 (-8875 5250)(-8800 5250);
WIRE 16 -1 (-8875 5300)(-8875 5250);
WIRE 16 -1 (-8875 5300)(-8800 5300);
WIRE 16 -1 (-8875 5350)(-8875 5300);
WIRE 16 -1 (-8875 5400)(-8875 5350);
WIRE 16 -1 (-8875 5350)(-8800 5350);
WIRE 16 -1 (-8875 5400)(-8800 5400);
WIRE 16 -1 (-8875 5450)(-8875 5400);
WIRE 16 -1 (-8875 5450)(-8800 5450);
WIRE 16 -1 (-8875 5500)(-8875 5450);
WIRE 16 -1 (-8875 5500)(-8800 5500);
WIRE 16 -1 (-8875 5550)(-8875 5500);
WIRE 16 -1 (-8875 5550)(-8800 5550);
WIRE 16 -1 (-8875 5600)(-8875 5550);
WIRE 16 -1 (-8875 5650)(-8875 5600);
WIRE 16 -1 (-8875 5600)(-8800 5600);
WIRE 16 -1 (-8875 5650)(-8800 5650);
WIRE 16 -1 (-8875 5700)(-8875 5650);
WIRE 16 -1 (-8875 5700)(-8800 5700);
WIRE 16 -1 (-8875 5750)(-8875 5700);
WIRE 16 -1 (-8875 5750)(-8800 5750);
WIRE 16 -1 (-8875 5800)(-8875 5750);
WIRE 16 -1 (-8875 5800)(-8800 5800);
WIRE 16 -1 (-8875 5850)(-8875 5800);
WIRE 16 -1 (-8875 5900)(-8875 5850);
WIRE 16 -1 (-8875 5850)(-8800 5850);
WIRE 16 -1 (-8875 5900)(-8800 5900);
WIRE 16 -1 (-8875 5950)(-8875 5900);
WIRE 16 -1 (-8875 5950)(-8800 5950);
WIRE 16 -1 (-8875 6000)(-8875 5950);
WIRE 16 -1 (-8875 6000)(-8800 6000);
WIRE 16 -1 (-8875 6050)(-8875 6000);
WIRE 16 -1 (-8875 6050)(-8800 6050);
WIRE 16 -1 (-8875 6100)(-8875 6050);
WIRE 16 -1 (-8875 6150)(-8875 6100);
WIRE 16 -1 (-8875 6100)(-8800 6100);
WIRE 16 -1 (-8875 6150)(-8800 6150);
WIRE 16 -1 (-8875 6200)(-8875 6150);
WIRE 16 -1 (-8875 6200)(-8800 6200);
WIRE 16 -1 (-8875 6250)(-8875 6200);
WIRE 16 -1 (-8875 6250)(-8800 6250);
WIRE 16 -1 (-8875 6300)(-8875 6250);
WIRE 16 -1 (-8875 6300)(-8800 6300);
WIRE 16 -1 (-8875 6350)(-8875 6300);
WIRE 16 -1 (-8875 6550)(-8875 6350);
WIRE 16 -1 (-8875 6350)(-8800 6350);
WIRE 16 -1 (-7425 550)(-7500 550);
WIRE 16 -1 (-7425 600)(-7425 550);
WIRE 16 -1 (-7425 650)(-7425 600);
WIRE 16 -1 (-7425 600)(-7500 600);
WIRE 16 -1 (-7425 700)(-7425 650);
WIRE 16 -1 (-7425 650)(-7500 650);
WIRE 16 -1 (-7425 750)(-7425 700);
WIRE 16 -1 (-7425 700)(-7500 700);
WIRE 16 -1 (-7425 800)(-7425 750);
WIRE 16 -1 (-7425 750)(-7500 750);
WIRE 16 -1 (-7425 800)(-7500 800);
WIRE 16 -1 (-7425 850)(-7425 800);
WIRE 16 -1 (-7425 900)(-7425 850);
WIRE 16 -1 (-7425 850)(-7500 850);
WIRE 16 -1 (-7425 900)(-7425 950);
WIRE 16 -1 (-7500 900)(-7425 900);
WIRE 16 -1 (-7425 1000)(-7425 950);
WIRE 16 -1 (-7425 950)(-7500 950);
WIRE 16 -1 (-7425 1050)(-7425 1000);
WIRE 16 -1 (-7425 1000)(-7500 1000);
WIRE 16 -1 (-7425 1100)(-7425 1050);
WIRE 16 -1 (-7425 1050)(-7500 1050);
WIRE 16 -1 (-7425 1150)(-7425 1100);
WIRE 16 -1 (-7425 1100)(-7500 1100);
WIRE 16 -1 (-7425 1200)(-7425 1150);
WIRE 16 -1 (-7425 1150)(-7500 1150);
WIRE 16 -1 (-7425 1200)(-7500 1200);
WIRE 16 -1 (-7425 1250)(-7425 1200);
WIRE 16 -1 (-7425 1300)(-7425 1250);
WIRE 16 -1 (-7425 1250)(-7500 1250);
WIRE 16 -1 (-7425 1350)(-7425 1300);
WIRE 16 -1 (-7425 1300)(-7500 1300);
WIRE 16 -1 (-7500 1350)(-7425 1350);
WIRE 16 -1 (-7425 1350)(-7425 1400);
WIRE 16 -1 (-7425 1450)(-7425 1400);
WIRE 16 -1 (-7425 1400)(-7500 1400);
WIRE 16 -1 (-7425 1450)(-7500 1450);
WIRE 16 -1 (-7425 1500)(-7425 1450);
WIRE 16 -1 (-7425 1550)(-7425 1500);
WIRE 16 -1 (-7425 1500)(-7500 1500);
WIRE 16 -1 (-7425 1600)(-7425 1550);
WIRE 16 -1 (-7425 1550)(-7500 1550);
WIRE 16 -1 (-7425 1650)(-7425 1600);
WIRE 16 -1 (-7425 1600)(-7500 1600);
WIRE 16 -1 (-7425 1700)(-7425 1650);
WIRE 16 -1 (-7425 1650)(-7500 1650);
WIRE 16 -1 (-7425 1700)(-7500 1700);
WIRE 16 -1 (-7425 1750)(-7425 1700);
WIRE 16 -1 (-7425 1800)(-7425 1750);
WIRE 16 -1 (-7425 1750)(-7500 1750);
WIRE 16 -1 (-7425 1800)(-7425 1850);
WIRE 16 -1 (-7500 1800)(-7425 1800);
WIRE 16 -1 (-7425 1900)(-7425 1850);
WIRE 16 -1 (-7425 1850)(-7500 1850);
WIRE 16 -1 (-7425 1950)(-7425 1900);
WIRE 16 -1 (-7425 1900)(-7500 1900);
WIRE 16 -1 (-7425 1950)(-7500 1950);
WIRE 16 -1 (-7425 2000)(-7425 1950);
WIRE 16 -1 (-7425 2050)(-7425 2000);
WIRE 16 -1 (-7425 2000)(-7500 2000);
WIRE 16 -1 (-7425 2100)(-7425 2050);
WIRE 16 -1 (-7425 2050)(-7500 2050);
WIRE 16 -1 (-7425 2150)(-7425 2100);
WIRE 16 -1 (-7425 2100)(-7500 2100);
WIRE 16 -1 (-7425 2200)(-7425 2150);
WIRE 16 -1 (-7425 2150)(-7500 2150);
WIRE 16 -1 (-7425 2250)(-7425 2200);
WIRE 16 -1 (-7425 2200)(-7500 2200);
WIRE 16 -1 (-7500 2250)(-7425 2250);
WIRE 16 -1 (-7425 2250)(-7425 2300);
WIRE 16 -1 (-7425 2350)(-7425 2300);
WIRE 16 -1 (-7425 2300)(-7500 2300);
WIRE 16 -1 (-7425 2350)(-7500 2350);
WIRE 16 -1 (-7425 2400)(-7425 2350);
WIRE 16 -1 (-7425 2450)(-7425 2400);
WIRE 16 -1 (-7425 2400)(-7500 2400);
WIRE 16 -1 (-7425 2500)(-7425 2450);
WIRE 16 -1 (-7425 2450)(-7500 2450);
WIRE 16 -1 (-7425 2550)(-7425 2500);
WIRE 16 -1 (-7425 2500)(-7500 2500);
WIRE 16 -1 (-7425 2600)(-7425 2550);
WIRE 16 -1 (-7425 2550)(-7500 2550);
WIRE 16 -1 (-7425 2600)(-7500 2600);
WIRE 16 -1 (-7425 2650)(-7425 2600);
WIRE 16 -1 (-7425 2700)(-7425 2650);
WIRE 16 -1 (-7425 2650)(-7500 2650);
WIRE 16 -1 (-7425 2700)(-7425 2750);
WIRE 16 -1 (-7500 2700)(-7425 2700);
WIRE 16 -1 (-7425 2800)(-7425 2750);
WIRE 16 -1 (-7425 2750)(-7500 2750);
WIRE 16 -1 (-7425 2850)(-7425 2800);
WIRE 16 -1 (-7425 2800)(-7500 2800);
WIRE 16 -1 (-7425 2850)(-7500 2850);
WIRE 16 -1 (-7425 2900)(-7425 2850);
WIRE 16 -1 (-7425 2950)(-7425 2900);
WIRE 16 -1 (-7425 2900)(-7500 2900);
WIRE 16 -1 (-7425 3000)(-7425 2950);
WIRE 16 -1 (-7425 2950)(-7500 2950);
WIRE 16 -1 (-7425 3050)(-7425 3000);
WIRE 16 -1 (-7425 3000)(-7500 3000);
WIRE 16 -1 (-7425 3100)(-7425 3050);
WIRE 16 -1 (-7425 3050)(-7500 3050);
WIRE 16 -1 (-7425 3100)(-7500 3100);
WIRE 16 -1 (-7425 3150)(-7425 3100);
WIRE 16 -1 (-7425 3150)(-7425 3200);
WIRE 16 -1 (-7500 3150)(-7425 3150);
WIRE 16 -1 (-7425 3200)(-7500 3200);
WIRE 16 -1 (-7425 3250)(-7425 3200);
WIRE 16 -1 (-7425 3250)(-7500 3250);
WIRE 16 -1 (-7425 3300)(-7425 3250);
WIRE 16 -1 (-7425 3350)(-7425 3300);
WIRE 16 -1 (-7425 3300)(-7500 3300);
WIRE 16 -1 (-7425 3400)(-7425 3350);
WIRE 16 -1 (-7425 3350)(-7500 3350);
WIRE 16 -1 (-7425 3450)(-7425 3400);
WIRE 16 -1 (-7425 3400)(-7500 3400);
WIRE 16 -1 (-7425 3500)(-7425 3450);
WIRE 16 -1 (-7425 3450)(-7500 3450);
WIRE 16 -1 (-7425 3500)(-7500 3500);
WIRE 16 -1 (-7425 3550)(-7425 3500);
WIRE 16 -1 (-7425 3600)(-7425 3550);
WIRE 16 -1 (-7425 3550)(-7500 3550);
WIRE 16 -1 (-7425 3600)(-7425 3650);
WIRE 16 -1 (-7500 3600)(-7425 3600);
WIRE 16 -1 (-7425 3700)(-7425 3650);
WIRE 16 -1 (-7425 3650)(-7500 3650);
WIRE 16 -1 (-7425 3750)(-7425 3700);
WIRE 16 -1 (-7425 3700)(-7500 3700);
WIRE 16 -1 (-7425 3750)(-7500 3750);
WIRE 16 -1 (-7425 3800)(-7425 3750);
WIRE 16 -1 (-7425 3850)(-7425 3800);
WIRE 16 -1 (-7425 3800)(-7500 3800);
WIRE 16 -1 (-7425 3900)(-7425 3850);
WIRE 16 -1 (-7425 3850)(-7500 3850);
WIRE 16 -1 (-7425 3950)(-7425 3900);
WIRE 16 -1 (-7425 3900)(-7500 3900);
WIRE 16 -1 (-7425 4000)(-7425 3950);
WIRE 16 -1 (-7425 3950)(-7500 3950);
WIRE 16 -1 (-7425 4000)(-7500 4000);
WIRE 16 -1 (-7425 4050)(-7425 4000);
WIRE 16 -1 (-7425 4050)(-7425 4100);
WIRE 16 -1 (-7500 4050)(-7425 4050);
WIRE 16 -1 (-7425 4150)(-7425 4100);
WIRE 16 -1 (-7425 4100)(-7500 4100);
WIRE 16 -1 (-7425 4200)(-7425 4150);
WIRE 16 -1 (-7425 4150)(-7500 4150);
WIRE 16 -1 (-7425 4250)(-7425 4200);
WIRE 16 -1 (-7425 4200)(-7500 4200);
WIRE 16 -1 (-7425 4300)(-7425 4250);
WIRE 16 -1 (-7425 4250)(-7500 4250);
WIRE 16 -1 (-7425 4350)(-7425 4300);
WIRE 16 -1 (-7425 4300)(-7500 4300);
WIRE 16 -1 (-7425 4400)(-7425 4350);
WIRE 16 -1 (-7425 4350)(-7500 4350);
WIRE 16 -1 (-7425 4400)(-7500 4400);
WIRE 16 -1 (-7425 4450)(-7425 4400);
WIRE 16 -1 (-7425 4500)(-7425 4450);
WIRE 16 -1 (-7425 4450)(-7500 4450);
WIRE 16 -1 (-7425 4500)(-7425 4550);
WIRE 16 -1 (-7500 4500)(-7425 4500);
WIRE 16 -1 (-7425 4600)(-7425 4550);
WIRE 16 -1 (-7425 4550)(-7500 4550);
WIRE 16 -1 (-7425 4650)(-7425 4600);
WIRE 16 -1 (-7425 4600)(-7500 4600);
WIRE 16 -1 (-7425 4650)(-7500 4650);
WIRE 16 -1 (-7425 4700)(-7425 4650);
WIRE 16 -1 (-7425 4750)(-7425 4700);
WIRE 16 -1 (-7425 4700)(-7500 4700);
WIRE 16 -1 (-7425 4800)(-7425 4750);
WIRE 16 -1 (-7425 4750)(-7500 4750);
WIRE 16 -1 (-7425 4850)(-7425 4800);
WIRE 16 -1 (-7425 4800)(-7500 4800);
WIRE 16 -1 (-7425 4900)(-7425 4850);
WIRE 16 -1 (-7425 4850)(-7500 4850);
WIRE 16 -1 (-7425 4900)(-7500 4900);
WIRE 16 -1 (-7425 4950)(-7425 4900);
WIRE 16 -1 (-7425 4950)(-7425 5000);
WIRE 16 -1 (-7500 4950)(-7425 4950);
WIRE 16 -1 (-7425 5050)(-7425 5000);
WIRE 16 -1 (-7425 5000)(-7500 5000);
WIRE 16 -1 (-7425 5100)(-7425 5050);
WIRE 16 -1 (-7425 5050)(-7500 5050);
WIRE 16 -1 (-7425 5150)(-7425 5100);
WIRE 16 -1 (-7425 5100)(-7500 5100);
WIRE 16 -1 (-7425 5150)(-7500 5150);
WIRE 16 -1 (-7425 5200)(-7425 5150);
WIRE 16 -1 (-7425 5250)(-7425 5200);
WIRE 16 -1 (-7425 5200)(-7500 5200);
WIRE 16 -1 (-7425 5300)(-7425 5250);
WIRE 16 -1 (-7425 5250)(-7500 5250);
WIRE 16 -1 (-7425 5350)(-7425 5300);
WIRE 16 -1 (-7425 5300)(-7500 5300);
WIRE 16 -1 (-7425 5400)(-7425 5350);
WIRE 16 -1 (-7425 5350)(-7500 5350);
WIRE 16 -1 (-7425 5400)(-7425 5450);
WIRE 16 -1 (-7500 5400)(-7425 5400);
WIRE 16 -1 (-7425 5500)(-7425 5450);
WIRE 16 -1 (-7425 5450)(-7500 5450);
WIRE 16 -1 (-7425 5550)(-7425 5500);
WIRE 16 -1 (-7425 5500)(-7500 5500);
WIRE 16 -1 (-7425 5550)(-7500 5550);
WIRE 16 -1 (-7425 5600)(-7425 5550);
WIRE 16 -1 (-7425 5650)(-7425 5600);
WIRE 16 -1 (-7425 5600)(-7500 5600);
WIRE 16 -1 (-7425 5700)(-7425 5650);
WIRE 16 -1 (-7425 5650)(-7500 5650);
WIRE 16 -1 (-7425 5750)(-7425 5700);
WIRE 16 -1 (-7425 5700)(-7500 5700);
WIRE 16 -1 (-7425 5800)(-7425 5750);
WIRE 16 -1 (-7425 5750)(-7500 5750);
WIRE 16 -1 (-7425 5800)(-7500 5800);
WIRE 16 -1 (-7425 5850)(-7425 5800);
WIRE 16 -1 (-7425 5850)(-7425 5900);
WIRE 16 -1 (-7500 5850)(-7425 5850);
WIRE 16 -1 (-7425 5950)(-7425 5900);
WIRE 16 -1 (-7425 5900)(-7500 5900);
WIRE 16 -1 (-7425 6000)(-7425 5950);
WIRE 16 -1 (-7425 5950)(-7500 5950);
WIRE 16 -1 (-7425 6050)(-7425 6000);
WIRE 16 -1 (-7425 6000)(-7500 6000);
WIRE 16 -1 (-7425 6050)(-7500 6050);
WIRE 16 -1 (-7425 6100)(-7425 6050);
WIRE 16 -1 (-7425 6150)(-7425 6100);
WIRE 16 -1 (-7425 6100)(-7500 6100);
WIRE 16 -1 (-7425 6200)(-7425 6150);
WIRE 16 -1 (-7425 6150)(-7500 6150);
WIRE 16 -1 (-7425 6250)(-7425 6200);
WIRE 16 -1 (-7425 6200)(-7500 6200);
WIRE 16 -1 (-7425 6300)(-7425 6250);
WIRE 16 -1 (-7425 6250)(-7500 6250);
WIRE 16 -1 (-7500 6300)(-7425 6300);
WIRE 16 -1 (-7425 6300)(-7425 6350);
WIRE 16 -1 (-7425 6550)(-7425 6350);
WIRE 16 -1 (-7500 6350)(-7425 6350);
WIRE 16 -1 (-6950 725)(-6875 725);
WIRE 16 -1 (-6950 775)(-6950 725);
WIRE 16 -1 (-6950 775)(-6875 775);
WIRE 16 -1 (-6950 775)(-6950 825);
WIRE 16 -1 (-6950 825)(-6875 825);
WIRE 16 -1 (-6950 825)(-6950 875);
WIRE 16 -1 (-6950 875)(-6875 875);
WIRE 16 -1 (-6950 875)(-6950 925);
WIRE 16 -1 (-6950 925)(-6875 925);
WIRE 16 -1 (-6950 925)(-6950 975);
WIRE 16 -1 (-6950 975)(-6950 1025);
WIRE 16 -1 (-6950 975)(-6875 975);
WIRE 16 -1 (-6950 1025)(-6875 1025);
WIRE 16 -1 (-6950 1025)(-6950 1075);
WIRE 16 -1 (-6950 1075)(-6875 1075);
WIRE 16 -1 (-6950 1075)(-6950 1125);
WIRE 16 -1 (-6950 1125)(-6875 1125);
WIRE 16 -1 (-6950 1125)(-6950 1175);
WIRE 16 -1 (-6875 1175)(-6950 1175);
WIRE 16 -1 (-6950 1175)(-6950 1225);
WIRE 16 -1 (-6950 1225)(-6875 1225);
WIRE 16 -1 (-6950 1225)(-6950 1275);
WIRE 16 -1 (-6950 1275)(-6875 1275);
WIRE 16 -1 (-6950 1275)(-6950 1325);
WIRE 16 -1 (-6950 1325)(-6875 1325);
WIRE 16 -1 (-6950 1325)(-6950 1375);
WIRE 16 -1 (-6950 1375)(-6875 1375);
WIRE 16 -1 (-6950 1375)(-6950 1425);
WIRE 16 -1 (-6950 1425)(-6875 1425);
WIRE 16 -1 (-6950 1425)(-6950 1475);
WIRE 16 -1 (-6950 1475)(-6875 1475);
WIRE 16 -1 (-6950 1475)(-6950 1525);
WIRE 16 -1 (-6950 1525)(-6950 1575);
WIRE 16 -1 (-6950 1525)(-6875 1525);
WIRE 16 -1 (-6950 1575)(-6875 1575);
WIRE 16 -1 (-6950 1575)(-6950 1625);
WIRE 16 -1 (-6950 1625)(-6875 1625);
WIRE 16 -1 (-6950 1625)(-6950 1675);
WIRE 16 -1 (-6950 1675)(-6875 1675);
WIRE 16 -1 (-6950 1675)(-6950 1725);
WIRE 16 -1 (-6950 1725)(-6875 1725);
WIRE 16 -1 (-6950 1725)(-6950 1775);
WIRE 16 -1 (-6950 1775)(-6875 1775);
WIRE 16 -1 (-6950 1775)(-6950 1825);
WIRE 16 -1 (-6950 1825)(-6875 1825);
WIRE 16 -1 (-6950 1825)(-6950 1875);
WIRE 16 -1 (-6875 1875)(-6950 1875);
WIRE 16 -1 (-6950 1875)(-6950 1925);
WIRE 16 -1 (-6950 1925)(-6875 1925);
WIRE 16 -1 (-6950 1925)(-6950 1975);
WIRE 16 -1 (-6950 1975)(-6875 1975);
WIRE 16 -1 (-6950 1975)(-6950 2025);
WIRE 16 -1 (-6950 2025)(-6950 2075);
WIRE 16 -1 (-6950 2025)(-6875 2025);
WIRE 16 -1 (-6950 2075)(-6875 2075);
WIRE 16 -1 (-6950 2075)(-6950 2125);
WIRE 16 -1 (-6950 2125)(-6875 2125);
WIRE 16 -1 (-6950 2125)(-6950 2175);
WIRE 16 -1 (-6950 2175)(-6875 2175);
WIRE 16 -1 (-6950 2175)(-6950 2225);
WIRE 16 -1 (-6950 2225)(-6875 2225);
WIRE 16 -1 (-6950 2225)(-6950 2275);
WIRE 16 -1 (-6950 2275)(-6875 2275);
WIRE 16 -1 (-6950 2275)(-6950 2325);
WIRE 16 -1 (-6950 2325)(-6875 2325);
WIRE 16 -1 (-6950 2325)(-6950 2375);
WIRE 16 -1 (-6950 2375)(-6875 2375);
WIRE 16 -1 (-6950 2375)(-6950 2425);
WIRE 16 -1 (-6950 2425)(-6875 2425);
WIRE 16 -1 (-6950 2425)(-6950 2475);
WIRE 16 -1 (-6950 2475)(-6875 2475);
WIRE 16 -1 (-6950 2475)(-6950 2525);
WIRE 16 -1 (-6950 2525)(-6950 2575);
WIRE 16 -1 (-6950 2525)(-6875 2525);
WIRE 16 -1 (-6875 2575)(-6950 2575);
WIRE 16 -1 (-6950 2575)(-6950 2625);
WIRE 16 -1 (-6950 2625)(-6875 2625);
WIRE 16 -1 (-6950 2625)(-6950 2675);
WIRE 16 -1 (-6950 2675)(-6875 2675);
WIRE 16 -1 (-6950 2675)(-6950 2725);
WIRE 16 -1 (-6950 2725)(-6875 2725);
WIRE 16 -1 (-6950 2725)(-6950 2775);
WIRE 16 -1 (-6950 2775)(-6875 2775);
WIRE 16 -1 (-6950 2775)(-6950 2825);
WIRE 16 -1 (-6950 2825)(-6875 2825);
WIRE 16 -1 (-6950 2825)(-6950 2875);
WIRE 16 -1 (-6950 2875)(-6875 2875);
WIRE 16 -1 (-6950 2875)(-6950 2925);
WIRE 16 -1 (-6950 2925)(-6875 2925);
WIRE 16 -1 (-6950 2925)(-6950 2975);
WIRE 16 -1 (-6950 2975)(-6875 2975);
WIRE 16 -1 (-6950 2975)(-6950 3025);
WIRE 16 -1 (-6950 3025)(-6950 3075);
WIRE 16 -1 (-6950 3025)(-6875 3025);
WIRE 16 -1 (-6950 3075)(-6875 3075);
WIRE 16 -1 (-6950 3075)(-6950 3125);
WIRE 16 -1 (-6950 3125)(-6875 3125);
WIRE 16 -1 (-6950 3125)(-6950 3175);
WIRE 16 -1 (-6950 3175)(-6875 3175);
WIRE 16 -1 (-6950 3175)(-6950 3225);
WIRE 16 -1 (-6950 3225)(-6875 3225);
WIRE 16 -1 (-6950 3225)(-6950 3275);
WIRE 16 -1 (-6875 3275)(-6950 3275);
WIRE 16 -1 (-6950 3275)(-6950 3325);
WIRE 16 -1 (-6950 3325)(-6875 3325);
WIRE 16 -1 (-6950 3325)(-6950 3375);
WIRE 16 -1 (-6950 3375)(-6875 3375);
WIRE 16 -1 (-6950 3375)(-6950 3425);
WIRE 16 -1 (-6950 3425)(-6875 3425);
WIRE 16 -1 (-6950 3425)(-6950 3475);
WIRE 16 -1 (-6950 3475)(-6875 3475);
WIRE 16 -1 (-6950 3475)(-6950 3525);
WIRE 16 -1 (-6950 3525)(-6875 3525);
WIRE 16 -1 (-6950 3525)(-6950 3575);
WIRE 16 -1 (-6950 3575)(-6950 3625);
WIRE 16 -1 (-6950 3575)(-6875 3575);
WIRE 16 -1 (-6950 3625)(-6875 3625);
WIRE 16 -1 (-6950 3625)(-6950 3675);
WIRE 16 -1 (-6950 3675)(-6875 3675);
WIRE 16 -1 (-6950 3675)(-6950 3725);
WIRE 16 -1 (-6950 3725)(-6875 3725);
WIRE 16 -1 (-6950 3725)(-6950 3775);
WIRE 16 -1 (-6950 3775)(-6875 3775);
WIRE 16 -1 (-6950 3775)(-6950 3825);
WIRE 16 -1 (-6950 3825)(-6875 3825);
WIRE 16 -1 (-6950 3825)(-6950 3875);
WIRE 16 -1 (-6950 3875)(-6875 3875);
WIRE 16 -1 (-6950 3875)(-6950 3925);
WIRE 16 -1 (-6950 3925)(-6875 3925);
WIRE 16 -1 (-6950 3925)(-6950 3975);
WIRE 16 -1 (-6875 3975)(-6950 3975);
WIRE 16 -1 (-6950 3975)(-6950 4025);
WIRE 16 -1 (-6950 4025)(-6875 4025);
WIRE 16 -1 (-6950 4025)(-6950 4075);
WIRE 16 -1 (-6950 4075)(-6950 4125);
WIRE 16 -1 (-6950 4075)(-6875 4075);
WIRE 16 -1 (-6950 4125)(-6875 4125);
WIRE 16 -1 (-6950 4125)(-6950 4175);
WIRE 16 -1 (-6950 4175)(-6875 4175);
WIRE 16 -1 (-6950 4175)(-6950 4225);
WIRE 16 -1 (-6950 4225)(-6875 4225);
WIRE 16 -1 (-6950 4225)(-6950 4275);
WIRE 16 -1 (-6950 4275)(-6875 4275);
WIRE 16 -1 (-6950 4275)(-6950 4325);
WIRE 16 -1 (-6950 4325)(-6875 4325);
WIRE 16 -1 (-6950 4325)(-6950 4375);
WIRE 16 -1 (-6950 4375)(-6875 4375);
WIRE 16 -1 (-6950 4375)(-6950 4425);
WIRE 16 -1 (-6950 4425)(-6875 4425);
WIRE 16 -1 (-6950 4425)(-6950 4475);
WIRE 16 -1 (-6950 4475)(-6875 4475);
WIRE 16 -1 (-6950 4475)(-6950 4525);
WIRE 16 -1 (-6950 4525)(-6875 4525);
WIRE 16 -1 (-6950 4525)(-6950 4575);
WIRE 16 -1 (-6950 4575)(-6950 4625);
WIRE 16 -1 (-6950 4575)(-6875 4575);
WIRE 16 -1 (-6950 4625)(-6875 4625);
WIRE 16 -1 (-6950 4625)(-6950 4675);
WIRE 16 -1 (-6875 4675)(-6950 4675);
WIRE 16 -1 (-6950 4675)(-6950 4725);
WIRE 16 -1 (-6950 4725)(-6875 4725);
WIRE 16 -1 (-6950 4725)(-6950 4775);
WIRE 16 -1 (-6950 4775)(-6875 4775);
WIRE 16 -1 (-6950 4775)(-6950 4825);
WIRE 16 -1 (-6950 4825)(-6875 4825);
WIRE 16 -1 (-6950 4825)(-6950 4875);
WIRE 16 -1 (-6950 4875)(-6875 4875);
WIRE 16 -1 (-6950 4875)(-6950 4925);
WIRE 16 -1 (-6950 4925)(-6875 4925);
WIRE 16 -1 (-6950 4925)(-6950 4975);
WIRE 16 -1 (-6950 4975)(-6875 4975);
WIRE 16 -1 (-6950 4975)(-6950 5025);
WIRE 16 -1 (-6950 5025)(-6875 5025);
WIRE 16 -1 (-6950 5025)(-6950 5075);
WIRE 16 -1 (-6950 5075)(-6950 5125);
WIRE 16 -1 (-6950 5075)(-6875 5075);
WIRE 16 -1 (-6950 5125)(-6875 5125);
WIRE 16 -1 (-6950 5125)(-6950 5175);
WIRE 16 -1 (-6950 5175)(-6875 5175);
WIRE 16 -1 (-6950 5175)(-6950 5225);
WIRE 16 -1 (-6950 5225)(-6875 5225);
WIRE 16 -1 (-6950 5225)(-6950 5275);
WIRE 16 -1 (-6950 5275)(-6875 5275);
WIRE 16 -1 (-6950 5275)(-6950 5325);
WIRE 16 -1 (-6950 5325)(-6875 5325);
WIRE 16 -1 (-6950 5325)(-6950 5375);
WIRE 16 -1 (-6875 5375)(-6950 5375);
WIRE 16 -1 (-6950 5375)(-6950 5425);
WIRE 16 -1 (-6950 5425)(-6875 5425);
WIRE 16 -1 (-6950 5425)(-6950 5475);
WIRE 16 -1 (-6950 5475)(-6875 5475);
WIRE 16 -1 (-6950 5475)(-6950 5525);
WIRE 16 -1 (-6950 5525)(-6875 5525);
WIRE 16 -1 (-6950 5525)(-6950 5575);
WIRE 16 -1 (-6950 5575)(-6875 5575);
WIRE 16 -1 (-6950 5575)(-6950 5625);
WIRE 16 -1 (-6950 5625)(-6950 5675);
WIRE 16 -1 (-6950 5625)(-6875 5625);
WIRE 16 -1 (-6950 5675)(-6875 5675);
WIRE 16 -1 (-6950 5675)(-6950 5725);
WIRE 16 -1 (-6950 5725)(-6875 5725);
WIRE 16 -1 (-6950 5725)(-6950 5775);
WIRE 16 -1 (-6950 5775)(-6875 5775);
WIRE 16 -1 (-6950 5775)(-6950 5825);
WIRE 16 -1 (-6950 5825)(-6875 5825);
WIRE 16 -1 (-6950 5825)(-6950 5875);
WIRE 16 -1 (-6950 5875)(-6875 5875);
WIRE 16 -1 (-6950 5875)(-6950 5925);
WIRE 16 -1 (-6950 5925)(-6875 5925);
WIRE 16 -1 (-6950 5925)(-6950 5975);
WIRE 16 -1 (-6950 5975)(-6875 5975);
WIRE 16 -1 (-6950 5975)(-6950 6025);
WIRE 16 -1 (-6950 6025)(-6875 6025);
WIRE 16 -1 (-6950 6025)(-6950 6075);
WIRE 16 -1 (-6875 6075)(-6950 6075);
WIRE 16 -1 (-6950 6075)(-6950 6125);
WIRE 16 -1 (-6950 6275)(-6950 6125);
WIRE 16 -1 (-6875 6125)(-6950 6125);
WIRE 16 -1 (-5575 275)(-5525 275);
WIRE 16 -1 (-5525 325)(-5525 275);
WIRE 16 -1 (-5575 325)(-5525 325);
WIRE 16 -1 (-5525 325)(-5525 375);
WIRE 16 -1 (-5575 375)(-5525 375);
WIRE 16 -1 (-5525 425)(-5525 375);
WIRE 16 -1 (-5525 425)(-5525 475);
WIRE 16 -1 (-5575 425)(-5525 425);
WIRE 16 -1 (-5575 475)(-5525 475);
WIRE 16 -1 (-5525 475)(-5525 525);
WIRE 16 -1 (-5525 525)(-5525 575);
WIRE 16 -1 (-5575 525)(-5525 525);
WIRE 16 -1 (-5575 575)(-5525 575);
WIRE 16 -1 (-5525 575)(-5525 625);
WIRE 16 -1 (-5575 625)(-5525 625);
WIRE 16 -1 (-5525 625)(-5525 675);
WIRE 16 -1 (-5525 675)(-5525 725);
WIRE 16 -1 (-5575 675)(-5525 675);
WIRE 16 -1 (-5575 725)(-5525 725);
WIRE 16 -1 (-5525 725)(-5525 775);
WIRE 16 -1 (-5525 775)(-5525 825);
WIRE 16 -1 (-5575 775)(-5525 775);
WIRE 16 -1 (-5575 825)(-5525 825);
WIRE 16 -1 (-5525 825)(-5525 875);
WIRE 16 -1 (-5575 875)(-5525 875);
WIRE 16 -1 (-5525 875)(-5525 925);
WIRE 16 -1 (-5525 925)(-5525 975);
WIRE 16 -1 (-5575 925)(-5525 925);
WIRE 16 -1 (-5575 975)(-5525 975);
WIRE 16 -1 (-5525 975)(-5525 1025);
WIRE 16 -1 (-5525 1025)(-5525 1075);
WIRE 16 -1 (-5575 1025)(-5525 1025);
WIRE 16 -1 (-5575 1075)(-5525 1075);
WIRE 16 -1 (-5525 1075)(-5525 1125);
WIRE 16 -1 (-5575 1125)(-5525 1125);
WIRE 16 -1 (-5525 1125)(-5525 1175);
WIRE 16 -1 (-5525 1175)(-5525 1225);
WIRE 16 -1 (-5575 1175)(-5525 1175);
WIRE 16 -1 (-5575 1225)(-5525 1225);
WIRE 16 -1 (-5525 1225)(-5525 1275);
WIRE 16 -1 (-5575 1275)(-5525 1275);
WIRE 16 -1 (-5525 1275)(-5525 1325);
WIRE 16 -1 (-5525 1325)(-5525 1375);
WIRE 16 -1 (-5575 1325)(-5525 1325);
WIRE 16 -1 (-5575 1375)(-5525 1375);
WIRE 16 -1 (-5525 1375)(-5525 1425);
WIRE 16 -1 (-5525 1425)(-5525 1475);
WIRE 16 -1 (-5575 1425)(-5525 1425);
WIRE 16 -1 (-5575 1475)(-5525 1475);
WIRE 16 -1 (-5525 1475)(-5525 1525);
WIRE 16 -1 (-5575 1525)(-5525 1525);
WIRE 16 -1 (-5525 1525)(-5525 1575);
WIRE 16 -1 (-5525 1575)(-5525 1625);
WIRE 16 -1 (-5575 1575)(-5525 1575);
WIRE 16 -1 (-5575 1625)(-5525 1625);
WIRE 16 -1 (-5525 1625)(-5525 1675);
WIRE 16 -1 (-5525 1675)(-5525 1725);
WIRE 16 -1 (-5575 1675)(-5525 1675);
WIRE 16 -1 (-5575 1725)(-5525 1725);
WIRE 16 -1 (-5525 1725)(-5525 1775);
WIRE 16 -1 (-5575 1775)(-5525 1775);
WIRE 16 -1 (-5525 1775)(-5525 1825);
WIRE 16 -1 (-5525 1825)(-5525 1875);
WIRE 16 -1 (-5575 1825)(-5525 1825);
WIRE 16 -1 (-5575 1875)(-5525 1875);
WIRE 16 -1 (-5525 1875)(-5525 1925);
WIRE 16 -1 (-5525 1925)(-5525 1975);
WIRE 16 -1 (-5575 1925)(-5525 1925);
WIRE 16 -1 (-5575 1975)(-5525 1975);
WIRE 16 -1 (-5525 1975)(-5525 2025);
WIRE 16 -1 (-5575 2025)(-5525 2025);
WIRE 16 -1 (-5525 2025)(-5525 2075);
WIRE 16 -1 (-5525 2075)(-5525 2125);
WIRE 16 -1 (-5575 2075)(-5525 2075);
WIRE 16 -1 (-5575 2125)(-5525 2125);
WIRE 16 -1 (-5525 2125)(-5525 2175);
WIRE 16 -1 (-5575 2175)(-5525 2175);
WIRE 16 -1 (-5525 2175)(-5525 2225);
WIRE 16 -1 (-5525 2225)(-5525 2275);
WIRE 16 -1 (-5575 2225)(-5525 2225);
WIRE 16 -1 (-5575 2275)(-5525 2275);
WIRE 16 -1 (-5525 2275)(-5525 2325);
WIRE 16 -1 (-5525 2325)(-5525 2375);
WIRE 16 -1 (-5575 2325)(-5525 2325);
WIRE 16 -1 (-5575 2375)(-5525 2375);
WIRE 16 -1 (-5525 2375)(-5525 2425);
WIRE 16 -1 (-5575 2425)(-5525 2425);
WIRE 16 -1 (-5525 2425)(-5525 2475);
WIRE 16 -1 (-5525 2475)(-5525 2525);
WIRE 16 -1 (-5575 2475)(-5525 2475);
WIRE 16 -1 (-5575 2525)(-5525 2525);
WIRE 16 -1 (-5525 2525)(-5525 2575);
WIRE 16 -1 (-5525 2575)(-5525 2625);
WIRE 16 -1 (-5575 2575)(-5525 2575);
WIRE 16 -1 (-5575 2625)(-5525 2625);
WIRE 16 -1 (-5525 2625)(-5525 2675);
WIRE 16 -1 (-5575 2675)(-5525 2675);
WIRE 16 -1 (-5525 2675)(-5525 2725);
WIRE 16 -1 (-5525 2725)(-5525 2775);
WIRE 16 -1 (-5575 2725)(-5525 2725);
WIRE 16 -1 (-5575 2775)(-5525 2775);
WIRE 16 -1 (-5525 2775)(-5525 2825);
WIRE 16 -1 (-5525 2825)(-5525 2875);
WIRE 16 -1 (-5575 2825)(-5525 2825);
WIRE 16 -1 (-5575 2875)(-5525 2875);
WIRE 16 -1 (-5525 2875)(-5525 2925);
WIRE 16 -1 (-5575 2925)(-5525 2925);
WIRE 16 -1 (-5525 2925)(-5525 2975);
WIRE 16 -1 (-5525 2975)(-5525 3025);
WIRE 16 -1 (-5575 2975)(-5525 2975);
WIRE 16 -1 (-5575 3025)(-5525 3025);
WIRE 16 -1 (-5525 3025)(-5525 3075);
WIRE 16 -1 (-5525 3075)(-5525 3125);
WIRE 16 -1 (-5575 3075)(-5525 3075);
WIRE 16 -1 (-5575 3125)(-5525 3125);
WIRE 16 -1 (-5525 3125)(-5525 3175);
WIRE 16 -1 (-5575 3175)(-5525 3175);
WIRE 16 -1 (-5525 3175)(-5525 3225);
WIRE 16 -1 (-5525 3225)(-5525 3275);
WIRE 16 -1 (-5575 3225)(-5525 3225);
WIRE 16 -1 (-5575 3275)(-5525 3275);
WIRE 16 -1 (-5525 3275)(-5525 3325);
WIRE 16 -1 (-5575 3325)(-5525 3325);
WIRE 16 -1 (-5525 3325)(-5525 3375);
WIRE 16 -1 (-5525 3375)(-5525 3425);
WIRE 16 -1 (-5575 3375)(-5525 3375);
WIRE 16 -1 (-5575 3425)(-5525 3425);
WIRE 16 -1 (-5525 3425)(-5525 3475);
WIRE 16 -1 (-5525 3475)(-5525 3525);
WIRE 16 -1 (-5575 3475)(-5525 3475);
WIRE 16 -1 (-5575 3525)(-5525 3525);
WIRE 16 -1 (-5525 3525)(-5525 3575);
WIRE 16 -1 (-5575 3575)(-5525 3575);
WIRE 16 -1 (-5525 3575)(-5525 3625);
WIRE 16 -1 (-5525 3625)(-5525 3675);
WIRE 16 -1 (-5575 3625)(-5525 3625);
WIRE 16 -1 (-5575 3675)(-5525 3675);
WIRE 16 -1 (-5525 3675)(-5525 3725);
WIRE 16 -1 (-5525 3725)(-5525 3775);
WIRE 16 -1 (-5575 3725)(-5525 3725);
WIRE 16 -1 (-5575 3775)(-5525 3775);
WIRE 16 -1 (-5525 3775)(-5525 3825);
WIRE 16 -1 (-5575 3825)(-5525 3825);
WIRE 16 -1 (-5525 3825)(-5525 3875);
WIRE 16 -1 (-5525 3875)(-5525 3925);
WIRE 16 -1 (-5575 3875)(-5525 3875);
WIRE 16 -1 (-5575 3925)(-5525 3925);
WIRE 16 -1 (-5525 3925)(-5525 3975);
WIRE 16 -1 (-5525 3975)(-5525 4025);
WIRE 16 -1 (-5575 3975)(-5525 3975);
WIRE 16 -1 (-5575 4025)(-5525 4025);
WIRE 16 -1 (-5525 4025)(-5525 4075);
WIRE 16 -1 (-5575 4075)(-5525 4075);
WIRE 16 -1 (-5525 4075)(-5525 4125);
WIRE 16 -1 (-5525 4125)(-5525 4175);
WIRE 16 -1 (-5575 4125)(-5525 4125);
WIRE 16 -1 (-5575 4175)(-5525 4175);
WIRE 16 -1 (-5525 4175)(-5525 4225);
WIRE 16 -1 (-5525 4225)(-5525 4275);
WIRE 16 -1 (-5575 4225)(-5525 4225);
WIRE 16 -1 (-5575 4275)(-5525 4275);
WIRE 16 -1 (-5525 4275)(-5525 4325);
WIRE 16 -1 (-5575 4325)(-5525 4325);
WIRE 16 -1 (-5525 4325)(-5525 4375);
WIRE 16 -1 (-5525 4375)(-5525 4425);
WIRE 16 -1 (-5575 4375)(-5525 4375);
WIRE 16 -1 (-5575 4425)(-5525 4425);
WIRE 16 -1 (-5525 4425)(-5525 4475);
WIRE 16 -1 (-5575 4475)(-5525 4475);
WIRE 16 -1 (-5525 4475)(-5525 4525);
WIRE 16 -1 (-5525 4525)(-5525 4575);
WIRE 16 -1 (-5575 4525)(-5525 4525);
WIRE 16 -1 (-5575 4575)(-5525 4575);
WIRE 16 -1 (-5525 4575)(-5525 4625);
WIRE 16 -1 (-5525 4625)(-5525 4675);
WIRE 16 -1 (-5575 4625)(-5525 4625);
WIRE 16 -1 (-5575 4675)(-5525 4675);
WIRE 16 -1 (-5525 4675)(-5525 4725);
WIRE 16 -1 (-5575 4725)(-5525 4725);
WIRE 16 -1 (-5525 4725)(-5525 4775);
WIRE 16 -1 (-5525 4775)(-5525 4825);
WIRE 16 -1 (-5575 4775)(-5525 4775);
WIRE 16 -1 (-5575 4825)(-5525 4825);
WIRE 16 -1 (-5525 4825)(-5525 4875);
WIRE 16 -1 (-5525 4875)(-5525 4925);
WIRE 16 -1 (-5575 4875)(-5525 4875);
WIRE 16 -1 (-5575 4925)(-5525 4925);
WIRE 16 -1 (-5525 4925)(-5525 4975);
WIRE 16 -1 (-5575 4975)(-5525 4975);
WIRE 16 -1 (-5525 4975)(-5525 5025);
WIRE 16 -1 (-5525 5025)(-5525 5075);
WIRE 16 -1 (-5575 5025)(-5525 5025);
WIRE 16 -1 (-5575 5075)(-5525 5075);
WIRE 16 -1 (-5525 5075)(-5525 5125);
WIRE 16 -1 (-5525 5125)(-5525 5175);
WIRE 16 -1 (-5575 5125)(-5525 5125);
WIRE 16 -1 (-5575 5175)(-5525 5175);
WIRE 16 -1 (-5525 5175)(-5525 5225);
WIRE 16 -1 (-5575 5225)(-5525 5225);
WIRE 16 -1 (-5525 5225)(-5525 5275);
WIRE 16 -1 (-5525 5275)(-5525 5325);
WIRE 16 -1 (-5575 5275)(-5525 5275);
WIRE 16 -1 (-5575 5325)(-5525 5325);
WIRE 16 -1 (-5525 5325)(-5525 5375);
WIRE 16 -1 (-5575 5375)(-5525 5375);
WIRE 16 -1 (-5525 5375)(-5525 5425);
WIRE 16 -1 (-5525 5425)(-5525 5475);
WIRE 16 -1 (-5575 5425)(-5525 5425);
WIRE 16 -1 (-5575 5475)(-5525 5475);
WIRE 16 -1 (-5525 5475)(-5525 5525);
WIRE 16 -1 (-5525 5525)(-5525 5575);
WIRE 16 -1 (-5575 5525)(-5525 5525);
WIRE 16 -1 (-5575 5575)(-5525 5575);
WIRE 16 -1 (-5525 5575)(-5525 5625);
WIRE 16 -1 (-5575 5625)(-5525 5625);
WIRE 16 -1 (-5525 5625)(-5525 5675);
WIRE 16 -1 (-5525 5675)(-5525 5725);
WIRE 16 -1 (-5575 5675)(-5525 5675);
WIRE 16 -1 (-5575 5725)(-5525 5725);
WIRE 16 -1 (-5525 5725)(-5525 5775);
WIRE 16 -1 (-5525 5775)(-5525 5825);
WIRE 16 -1 (-5575 5775)(-5525 5775);
WIRE 16 -1 (-5575 5825)(-5525 5825);
WIRE 16 -1 (-5525 5825)(-5525 5875);
WIRE 16 -1 (-5575 5875)(-5525 5875);
WIRE 16 -1 (-5525 5875)(-5525 5925);
WIRE 16 -1 (-5525 5925)(-5525 5975);
WIRE 16 -1 (-5575 5925)(-5525 5925);
WIRE 16 -1 (-5575 5975)(-5525 5975);
WIRE 16 -1 (-5525 5975)(-5525 6025);
WIRE 16 -1 (-5525 6025)(-5525 6075);
WIRE 16 -1 (-5575 6025)(-5525 6025);
WIRE 16 -1 (-5575 6075)(-5525 6075);
WIRE 16 -1 (-5525 6075)(-5525 6125);
WIRE 16 -1 (-5575 6125)(-5525 6125);
WIRE 16 -1 (-5525 6125)(-5525 6175);
WIRE 16 -1 (-5525 6175)(-5525 6225);
WIRE 16 -1 (-5575 6175)(-5525 6175);
WIRE 16 -1 (-5575 6225)(-5525 6225);
WIRE 16 -1 (-5525 6225)(-5525 6275);
WIRE 16 -1 (-5525 6275)(-5525 6325);
WIRE 16 -1 (-5575 6275)(-5525 6275);
WIRE 16 -1 (-5575 6325)(-5525 6325);
WIRE 16 -1 (-5525 6325)(-5525 6375);
WIRE 16 -1 (-5575 6375)(-5525 6375);
WIRE 16 -1 (-5525 6375)(-5525 6425);
WIRE 16 -1 (-5525 6500)(-5525 6425);
WIRE 16 -1 (-5575 6425)(-5525 6425);
WIRE 16 -1 (-5125 3175)(-5075 3175);
WIRE 16 -1 (-5125 3225)(-5125 3175);
WIRE 16 -1 (-5125 3225)(-5075 3225);
WIRE 16 -1 (-5125 3275)(-5125 3225);
WIRE 16 -1 (-5125 3275)(-5075 3275);
WIRE 16 -1 (-5125 3325)(-5125 3275);
WIRE 16 -1 (-5125 3325)(-5075 3325);
WIRE 16 -1 (-5125 3375)(-5125 3325);
WIRE 16 -1 (-5125 3375)(-5075 3375);
WIRE 16 -1 (-5125 3425)(-5125 3375);
WIRE 16 -1 (-5125 3425)(-5075 3425);
WIRE 16 -1 (-5125 3475)(-5125 3425);
WIRE 16 -1 (-5125 3475)(-5075 3475);
WIRE 16 -1 (-5125 3525)(-5125 3475);
WIRE 16 -1 (-5125 3525)(-5075 3525);
WIRE 16 -1 (-5125 3575)(-5125 3525);
WIRE 16 -1 (-5125 3575)(-5075 3575);
WIRE 16 -1 (-5125 3625)(-5125 3575);
WIRE 16 -1 (-5125 3625)(-5075 3625);
WIRE 16 -1 (-5125 3675)(-5125 3625);
WIRE 16 -1 (-5125 3675)(-5075 3675);
WIRE 16 -1 (-5125 3725)(-5125 3675);
WIRE 16 -1 (-5125 3725)(-5075 3725);
WIRE 16 -1 (-5125 3775)(-5125 3725);
WIRE 16 -1 (-5125 3775)(-5075 3775);
WIRE 16 -1 (-5125 3825)(-5125 3775);
WIRE 16 -1 (-5125 3825)(-5075 3825);
WIRE 16 -1 (-5125 3875)(-5125 3825);
WIRE 16 -1 (-5125 3875)(-5075 3875);
WIRE 16 -1 (-5125 3925)(-5125 3875);
WIRE 16 -1 (-5125 3925)(-5075 3925);
WIRE 16 -1 (-5125 3975)(-5125 3925);
WIRE 16 -1 (-5125 3975)(-5075 3975);
WIRE 16 -1 (-5125 4025)(-5125 3975);
WIRE 16 -1 (-5125 4025)(-5075 4025);
WIRE 16 -1 (-5125 4075)(-5125 4025);
WIRE 16 -1 (-5125 4125)(-5125 4075);
WIRE 16 -1 (-5125 4075)(-5075 4075);
WIRE 16 -1 (-5125 4125)(-5075 4125);
WIRE 16 -1 (-5125 4175)(-5125 4125);
WIRE 16 -1 (-5125 4175)(-5075 4175);
WIRE 16 -1 (-5125 4225)(-5125 4175);
WIRE 16 -1 (-5125 4225)(-5075 4225);
WIRE 16 -1 (-5125 4275)(-5125 4225);
WIRE 16 -1 (-5125 4275)(-5075 4275);
WIRE 16 -1 (-5125 4325)(-5125 4275);
WIRE 16 -1 (-5125 4325)(-5075 4325);
WIRE 16 -1 (-5125 4375)(-5125 4325);
WIRE 16 -1 (-5125 4375)(-5075 4375);
WIRE 16 -1 (-5125 4425)(-5125 4375);
WIRE 16 -1 (-5125 4425)(-5075 4425);
WIRE 16 -1 (-5125 4475)(-5125 4425);
WIRE 16 -1 (-5125 4475)(-5075 4475);
WIRE 16 -1 (-5125 4525)(-5125 4475);
WIRE 16 -1 (-5125 4525)(-5075 4525);
WIRE 16 -1 (-5125 4575)(-5125 4525);
WIRE 16 -1 (-5125 4575)(-5075 4575);
WIRE 16 -1 (-5125 4625)(-5125 4575);
WIRE 16 -1 (-5125 4625)(-5075 4625);
WIRE 16 -1 (-5125 4675)(-5125 4625);
WIRE 16 -1 (-5125 4675)(-5075 4675);
WIRE 16 -1 (-5125 4725)(-5125 4675);
WIRE 16 -1 (-5125 4725)(-5075 4725);
WIRE 16 -1 (-5125 4775)(-5125 4725);
WIRE 16 -1 (-5125 4775)(-5075 4775);
WIRE 16 -1 (-5125 4825)(-5125 4775);
WIRE 16 -1 (-5125 4825)(-5075 4825);
WIRE 16 -1 (-5125 4875)(-5125 4825);
WIRE 16 -1 (-5125 4875)(-5075 4875);
WIRE 16 -1 (-5125 4925)(-5125 4875);
WIRE 16 -1 (-5125 4925)(-5075 4925);
WIRE 16 -1 (-5125 4975)(-5125 4925);
WIRE 16 -1 (-5125 4975)(-5075 4975);
WIRE 16 -1 (-5125 5025)(-5125 4975);
WIRE 16 -1 (-5125 5025)(-5075 5025);
WIRE 16 -1 (-5125 5075)(-5125 5025);
WIRE 16 -1 (-5125 5075)(-5075 5075);
WIRE 16 -1 (-5125 5125)(-5125 5075);
WIRE 16 -1 (-5125 5125)(-5075 5125);
WIRE 16 -1 (-5125 5175)(-5125 5125);
WIRE 16 -1 (-5125 5175)(-5075 5175);
WIRE 16 -1 (-5125 5225)(-5125 5175);
WIRE 16 -1 (-5125 5225)(-5075 5225);
WIRE 16 -1 (-5125 5275)(-5125 5225);
WIRE 16 -1 (-5125 5275)(-5075 5275);
WIRE 16 -1 (-5125 5325)(-5125 5275);
WIRE 16 -1 (-5125 5325)(-5075 5325);
WIRE 16 -1 (-5125 5375)(-5125 5325);
WIRE 16 -1 (-5125 5375)(-5075 5375);
WIRE 16 -1 (-5125 5425)(-5125 5375);
WIRE 16 -1 (-5125 5425)(-5075 5425);
WIRE 16 -1 (-5125 5475)(-5125 5425);
WIRE 16 -1 (-5125 5475)(-5075 5475);
WIRE 16 -1 (-5125 5525)(-5125 5475);
WIRE 16 -1 (-5125 5525)(-5075 5525);
WIRE 16 -1 (-5125 5575)(-5125 5525);
WIRE 16 -1 (-5125 5575)(-5075 5575);
WIRE 16 -1 (-5125 5625)(-5125 5575);
WIRE 16 -1 (-5125 5625)(-5075 5625);
WIRE 16 -1 (-5125 5675)(-5125 5625);
WIRE 16 -1 (-5125 5675)(-5075 5675);
WIRE 16 -1 (-5125 5725)(-5125 5675);
WIRE 16 -1 (-5125 5725)(-5075 5725);
WIRE 16 -1 (-5125 5775)(-5125 5725);
WIRE 16 -1 (-5125 5775)(-5075 5775);
WIRE 16 -1 (-5125 5825)(-5125 5775);
WIRE 16 -1 (-5125 5825)(-5075 5825);
WIRE 16 -1 (-5125 5875)(-5125 5825);
WIRE 16 -1 (-5125 5875)(-5075 5875);
WIRE 16 -1 (-5125 5925)(-5125 5875);
WIRE 16 -1 (-5125 5925)(-5075 5925);
WIRE 16 -1 (-5125 5975)(-5125 5925);
WIRE 16 -1 (-5125 5975)(-5075 5975);
WIRE 16 -1 (-5125 6025)(-5125 5975);
WIRE 16 -1 (-5125 6025)(-5075 6025);
WIRE 16 -1 (-5125 6075)(-5125 6025);
WIRE 16 -1 (-5125 6075)(-5075 6075);
WIRE 16 -1 (-5125 6125)(-5125 6075);
WIRE 16 -1 (-5125 6200)(-5125 6125);
WIRE 16 -1 (-5125 6125)(-5075 6125);
WIRE 16 -1 (-3450 825)(-3725 825);
WIRE 16 -1 (-3725 825)(-3725 875);
WIRE 16 -1 (-3725 1000)(-3725 875);
WIRE 16 -1 (-3725 875)(-3450 875);
WIRE 16 -1 (-3725 1125)(-3450 1125);
WIRE 16 -1 (-3725 1475)(-3725 1125);
WIRE 16 -1 (-3725 1475)(-3450 1475);
WIRE 16 -1 (-3725 1525)(-3725 1475);
WIRE 16 -1 (-3725 1525)(-3450 1525);
WIRE 16 -1 (-3725 1575)(-3725 1525);
WIRE 16 -1 (-3725 1575)(-3450 1575);
WIRE 16 -1 (-3725 1625)(-3725 1575);
WIRE 16 -1 (-3725 1625)(-3450 1625);
WIRE 16 -1 (-3725 1675)(-3725 1625);
WIRE 16 -1 (-3725 1675)(-3450 1675);
WIRE 16 -1 (-3725 1725)(-3725 1675);
WIRE 16 -1 (-3725 1725)(-3450 1725);
WIRE 16 -1 (-3725 1775)(-3725 1725);
WIRE 16 -1 (-3725 1775)(-3450 1775);
WIRE 16 -1 (-3725 1825)(-3725 1775);
WIRE 16 -1 (-3725 1825)(-3450 1825);
WIRE 16 -1 (-3725 1875)(-3725 1825);
WIRE 16 -1 (-3725 1875)(-3450 1875);
WIRE 16 -1 (-3725 1925)(-3725 1875);
WIRE 16 -1 (-3725 1925)(-3450 1925);
WIRE 16 -1 (-3725 1975)(-3725 1925);
WIRE 16 -1 (-3725 1975)(-3450 1975);
WIRE 16 -1 (-3725 2025)(-3725 1975);
WIRE 16 -1 (-3725 2025)(-3725 2075);
WIRE 16 -1 (-3725 2025)(-3450 2025);
WIRE 16 -1 (-3725 2075)(-3450 2075);
WIRE 16 -1 (-3725 2125)(-3725 2075);
WIRE 16 -1 (-3725 2125)(-3450 2125);
WIRE 16 -1 (-3725 2175)(-3725 2125);
WIRE 16 -1 (-3725 2175)(-3450 2175);
WIRE 16 -1 (-3725 2225)(-3725 2175);
WIRE 16 -1 (-3725 2225)(-3450 2225);
WIRE 16 -1 (-3725 2275)(-3725 2225);
WIRE 16 -1 (-3725 2275)(-3450 2275);
WIRE 16 -1 (-3725 2325)(-3725 2275);
WIRE 16 -1 (-3725 2325)(-3450 2325);
WIRE 16 -1 (-3725 2375)(-3725 2325);
WIRE 16 -1 (-3725 2375)(-3450 2375);
WIRE 16 -1 (-3725 2425)(-3725 2375);
WIRE 16 -1 (-3725 2425)(-3450 2425);
WIRE 16 -1 (-3725 2475)(-3725 2425);
WIRE 16 -1 (-3725 2475)(-3450 2475);
WIRE 16 -1 (-3725 2575)(-3725 2475);
WIRE 16 -1 (-3450 2575)(-3725 2575);
WIRE 16 -1 (-3725 2650)(-3725 2575);
WIRE 16 -1 (-3550 2675)(-3450 2675);
WIRE 16 -1 (-3550 2675)(-3550 2725);
WIRE 16 -1 (-3550 2725)(-3450 2725);
WIRE 16 -1 (-3550 2725)(-3550 2775);
WIRE 16 -1 (-3550 2775)(-3550 2825);
WIRE 16 -1 (-3550 2775)(-3450 2775);
WIRE 16 -1 (-3550 2825)(-3450 2825);
WIRE 16 -1 (-3550 2825)(-3550 2875);
WIRE 16 -1 (-3550 2875)(-3450 2875);
WIRE 16 -1 (-3550 2875)(-3550 2925);
WIRE 16 -1 (-3450 2925)(-3550 2925);
WIRE 16 -1 (-3550 2925)(-3550 2975);
WIRE 16 -1 (-3550 2975)(-3450 2975);
WIRE 16 -1 (-3550 2975)(-3550 3025);
WIRE 16 -1 (-3550 3025)(-3550 3075);
WIRE 16 -1 (-3550 3025)(-3450 3025);
WIRE 16 -1 (-3550 3075)(-3450 3075);
WIRE 16 -1 (-3550 3075)(-3550 3125);
WIRE 16 -1 (-3550 3125)(-3450 3125);
WIRE 16 -1 (-3550 3125)(-3550 3175);
WIRE 16 -1 (-3550 3175)(-3450 3175);
WIRE 16 -1 (-3550 3175)(-3550 3225);
WIRE 16 -1 (-3450 3225)(-3550 3225);
WIRE 16 -1 (-3550 3225)(-3550 3275);
WIRE 16 -1 (-3550 3275)(-3450 3275);
WIRE 16 -1 (-3550 3275)(-3550 3325);
WIRE 16 -1 (-3550 3325)(-3550 3375);
WIRE 16 -1 (-3550 3325)(-3450 3325);
WIRE 16 -1 (-3550 3375)(-3450 3375);
WIRE 16 -1 (-3550 3375)(-3550 3425);
WIRE 16 -1 (-3550 3425)(-3450 3425);
WIRE 16 -1 (-3550 3425)(-3550 3475);
WIRE 16 -1 (-3550 3475)(-3450 3475);
WIRE 16 -1 (-3550 3475)(-3550 3525);
WIRE 16 -1 (-3450 3525)(-3550 3525);
WIRE 16 -1 (-3550 3525)(-3550 3575);
WIRE 16 -1 (-3550 3575)(-3550 3625);
WIRE 16 -1 (-3550 3575)(-3450 3575);
WIRE 16 -1 (-3550 3625)(-3450 3625);
WIRE 16 -1 (-3550 3625)(-3550 3675);
WIRE 16 -1 (-3550 3675)(-3450 3675);
WIRE 16 -1 (-3550 3675)(-3550 3725);
WIRE 16 -1 (-3450 3725)(-3550 3725);
WIRE 16 -1 (-3550 3725)(-3550 3775);
WIRE 16 -1 (-3550 3775)(-3450 3775);
WIRE 16 -1 (-3550 3775)(-3550 3825);
WIRE 16 -1 (-3550 3825)(-3550 3875);
WIRE 16 -1 (-3550 3825)(-3450 3825);
WIRE 16 -1 (-3550 3875)(-3450 3875);
WIRE 16 -1 (-3550 3925)(-3550 3875);
WIRE 16 -1 (-3550 3925)(-3450 3925);
WIRE 16 -1 (-3550 3975)(-3550 3925);
WIRE 16 -1 (-3550 3975)(-3450 3975);
WIRE 16 -1 (-3550 4025)(-3550 3975);
WIRE 16 -1 (-3450 4025)(-3550 4025);
WIRE 16 -1 (-3550 4075)(-3550 4025);
WIRE 16 -1 (-3550 4125)(-3550 4075);
WIRE 16 -1 (-3550 4075)(-3450 4075);
WIRE 16 -1 (-3550 4125)(-3450 4125);
WIRE 16 -1 (-3550 4175)(-3550 4125);
WIRE 16 -1 (-3550 4175)(-3450 4175);
WIRE 16 -1 (-3550 4225)(-3550 4175);
WIRE 16 -1 (-3550 4225)(-3450 4225);
WIRE 16 -1 (-3550 4275)(-3550 4225);
WIRE 16 -1 (-3550 4275)(-3450 4275);
WIRE 16 -1 (-3550 4325)(-3550 4275);
WIRE 16 -1 (-3550 4375)(-3550 4325);
WIRE 16 -1 (-3450 4325)(-3550 4325);
WIRE 16 -1 (-3550 4375)(-3450 4375);
WIRE 16 -1 (-3550 4425)(-3550 4375);
WIRE 16 -1 (-3550 4425)(-3450 4425);
WIRE 16 -1 (-3550 4475)(-3550 4425);
WIRE 16 -1 (-3550 4475)(-3450 4475);
WIRE 16 -1 (-3550 4525)(-3550 4475);
WIRE 16 -1 (-3550 4525)(-3450 4525);
WIRE 16 -1 (-3550 4575)(-3550 4525);
WIRE 16 -1 (-3550 4625)(-3550 4575);
WIRE 16 -1 (-3550 4575)(-3450 4575);
WIRE 16 -1 (-3450 4625)(-3550 4625);
WIRE 16 -1 (-3550 4675)(-3550 4625);
WIRE 16 -1 (-3550 4675)(-3450 4675);
WIRE 16 -1 (-3550 4725)(-3550 4675);
WIRE 16 -1 (-3550 4725)(-3450 4725);
WIRE 16 -1 (-3550 4775)(-3550 4725);
WIRE 16 -1 (-3550 4775)(-3450 4775);
WIRE 16 -1 (-3550 4825)(-3550 4775);
WIRE 16 -1 (-3550 4875)(-3550 4825);
WIRE 16 -1 (-3550 4825)(-3450 4825);
WIRE 16 -1 (-3550 4875)(-3450 4875);
WIRE 16 -1 (-3550 4925)(-3550 4875);
WIRE 16 -1 (-3450 4925)(-3550 4925);
WIRE 16 -1 (-3550 4975)(-3550 4925);
WIRE 16 -1 (-3550 4975)(-3450 4975);
WIRE 16 -1 (-3550 5025)(-3550 4975);
WIRE 16 -1 (-3550 5025)(-3450 5025);
WIRE 16 -1 (-3550 5075)(-3550 5025);
WIRE 16 -1 (-3550 5125)(-3550 5075);
WIRE 16 -1 (-3550 5075)(-3450 5075);
WIRE 16 -1 (-3550 5125)(-3450 5125);
WIRE 16 -1 (-3550 5175)(-3550 5125);
WIRE 16 -1 (-3550 5175)(-3450 5175);
WIRE 16 -1 (-3550 5225)(-3550 5175);
WIRE 16 -1 (-3450 5225)(-3550 5225);
WIRE 16 -1 (-3550 5275)(-3550 5225);
WIRE 16 -1 (-3550 5275)(-3450 5275);
WIRE 16 -1 (-3550 5325)(-3550 5275);
WIRE 16 -1 (-3550 5325)(-3450 5325);
WIRE 16 -1 (-3550 5375)(-3550 5325);
WIRE 16 -1 (-3550 5425)(-3550 5375);
WIRE 16 -1 (-3550 5375)(-3450 5375);
WIRE 16 -1 (-3550 5425)(-3450 5425);
WIRE 16 -1 (-3550 5475)(-3550 5425);
WIRE 16 -1 (-3550 5475)(-3450 5475);
WIRE 16 -1 (-3550 5525)(-3550 5475);
WIRE 16 -1 (-3450 5525)(-3550 5525);
WIRE 16 -1 (-3550 5575)(-3550 5525);
WIRE 16 -1 (-3550 5575)(-3450 5575);
WIRE 16 -1 (-3550 5625)(-3550 5575);
WIRE 16 -1 (-3550 5675)(-3550 5625);
WIRE 16 -1 (-3550 5625)(-3450 5625);
WIRE 16 -1 (-3550 5675)(-3450 5675);
WIRE 16 -1 (-3550 5725)(-3550 5675);
WIRE 16 -1 (-3550 5725)(-3450 5725);
WIRE 16 -1 (-3550 5775)(-3550 5725);
WIRE 16 -1 (-3550 5775)(-3450 5775);
WIRE 16 -1 (-3550 5825)(-3550 5775);
WIRE 16 -1 (-3450 5825)(-3550 5825);
WIRE 16 -1 (-3550 5875)(-3550 5825);
WIRE 16 -1 (-3550 5925)(-3550 5875);
WIRE 16 -1 (-3550 5875)(-3450 5875);
WIRE 16 -1 (-3550 5925)(-3450 5925);
WIRE 16 -1 (-3550 5975)(-3550 5925);
WIRE 16 -1 (-3550 5975)(-3450 5975);
WIRE 16 -1 (-3550 6025)(-3550 5975);
WIRE 16 -1 (-3550 6025)(-3450 6025);
WIRE 16 -1 (-3550 6075)(-3550 6025);
WIRE 16 -1 (-3550 6075)(-3450 6075);
WIRE 16 -1 (-3550 6125)(-3550 6075);
WIRE 16 -1 (-3550 6175)(-3550 6125);
WIRE 16 -1 (-3450 6125)(-3550 6125);
WIRE 16 -1 (-3550 6175)(-3450 6175);
WIRE 16 -1 (-3550 6225)(-3550 6175);
WIRE 16 -1 (-3550 6225)(-3450 6225);
WIRE 16 -1 (-3550 6275)(-3550 6225);
WIRE 16 -1 (-3550 6275)(-3450 6275);
WIRE 16 -1 (-3550 6325)(-3550 6275);
WIRE 16 -1 (-3550 6325)(-3450 6325);
WIRE 16 -1 (-3550 6375)(-3550 6325);
WIRE 16 -1 (-3550 6425)(-3550 6375);
WIRE 16 -1 (-3550 6375)(-3450 6375);
WIRE 16 -1 (-3450 6425)(-3550 6425);
WIRE 16 -1 (-3550 6475)(-3550 6425);
WIRE 16 -1 (-3450 6475)(-3550 6475);
WIRE 16 -1 (-3550 6525)(-3550 6475);
WIRE 16 -1 (-3825 3625)(-3825 3575);
WIRE 16 -1 (-3825 3675)(-3825 3625);
WIRE 16 -1 (-3825 3625)(-3875 3625);
WIRE 16 -1 (-3825 3575)(-3875 3575);
WIRE 16 -1 (-3825 3725)(-3825 3675);
WIRE 16 -1 (-3825 3675)(-3875 3675);
WIRE 16 -1 (-3825 3775)(-3825 3725);
WIRE 16 -1 (-3825 3725)(-3875 3725);
WIRE 16 -1 (-3825 3825)(-3825 3775);
WIRE 16 -1 (-3825 3775)(-3875 3775);
WIRE 16 -1 (-3825 3875)(-3825 3825);
WIRE 16 -1 (-3825 3825)(-3875 3825);
WIRE 16 -1 (-3825 3925)(-3825 3875);
WIRE 16 -1 (-3825 3875)(-3875 3875);
WIRE 16 -1 (-3825 3975)(-3825 3925);
WIRE 16 -1 (-3825 3925)(-3875 3925);
WIRE 16 -1 (-3825 4025)(-3825 3975);
WIRE 16 -1 (-3825 3975)(-3875 3975);
WIRE 16 -1 (-3825 4075)(-3825 4025);
WIRE 16 -1 (-3825 4025)(-3875 4025);
WIRE 16 -1 (-3825 4125)(-3825 4075);
WIRE 16 -1 (-3825 4075)(-3875 4075);
WIRE 16 -1 (-3825 4175)(-3825 4125);
WIRE 16 -1 (-3825 4125)(-3875 4125);
WIRE 16 -1 (-3825 4225)(-3825 4175);
WIRE 16 -1 (-3825 4175)(-3875 4175);
WIRE 16 -1 (-3825 4275)(-3825 4225);
WIRE 16 -1 (-3825 4225)(-3875 4225);
WIRE 16 -1 (-3825 4325)(-3825 4275);
WIRE 16 -1 (-3825 4275)(-3875 4275);
WIRE 16 -1 (-3825 4375)(-3825 4325);
WIRE 16 -1 (-3825 4325)(-3875 4325);
WIRE 16 -1 (-3825 4425)(-3825 4375);
WIRE 16 -1 (-3825 4375)(-3875 4375);
WIRE 16 -1 (-3825 4475)(-3825 4425);
WIRE 16 -1 (-3825 4425)(-3875 4425);
WIRE 16 -1 (-3825 4525)(-3825 4475);
WIRE 16 -1 (-3825 4475)(-3875 4475);
WIRE 16 -1 (-3825 4575)(-3825 4525);
WIRE 16 -1 (-3825 4525)(-3875 4525);
WIRE 16 -1 (-3825 4625)(-3825 4575);
WIRE 16 -1 (-3825 4575)(-3875 4575);
WIRE 16 -1 (-3825 4675)(-3825 4625);
WIRE 16 -1 (-3825 4625)(-3875 4625);
WIRE 16 -1 (-3825 4725)(-3825 4675);
WIRE 16 -1 (-3825 4675)(-3875 4675);
WIRE 16 -1 (-3825 4775)(-3825 4725);
WIRE 16 -1 (-3825 4725)(-3875 4725);
WIRE 16 -1 (-3825 4825)(-3825 4775);
WIRE 16 -1 (-3825 4775)(-3875 4775);
WIRE 16 -1 (-3825 4875)(-3825 4825);
WIRE 16 -1 (-3825 4825)(-3875 4825);
WIRE 16 -1 (-3825 4925)(-3825 4875);
WIRE 16 -1 (-3825 4875)(-3875 4875);
WIRE 16 -1 (-3825 4975)(-3825 4925);
WIRE 16 -1 (-3825 4925)(-3875 4925);
WIRE 16 -1 (-3825 5025)(-3825 4975);
WIRE 16 -1 (-3825 4975)(-3875 4975);
WIRE 16 -1 (-3825 5075)(-3825 5025);
WIRE 16 -1 (-3825 5025)(-3875 5025);
WIRE 16 -1 (-3825 5125)(-3825 5075);
WIRE 16 -1 (-3825 5075)(-3875 5075);
WIRE 16 -1 (-3825 5175)(-3825 5125);
WIRE 16 -1 (-3825 5125)(-3875 5125);
WIRE 16 -1 (-3825 5225)(-3825 5175);
WIRE 16 -1 (-3825 5175)(-3875 5175);
WIRE 16 -1 (-3825 5275)(-3825 5225);
WIRE 16 -1 (-3825 5225)(-3875 5225);
WIRE 16 -1 (-3825 5325)(-3825 5275);
WIRE 16 -1 (-3825 5275)(-3875 5275);
WIRE 16 -1 (-3825 5375)(-3825 5325);
WIRE 16 -1 (-3825 5325)(-3875 5325);
WIRE 16 -1 (-3825 5425)(-3825 5375);
WIRE 16 -1 (-3825 5375)(-3875 5375);
WIRE 16 -1 (-3825 5475)(-3825 5425);
WIRE 16 -1 (-3825 5425)(-3875 5425);
WIRE 16 -1 (-3825 5525)(-3825 5475);
WIRE 16 -1 (-3825 5475)(-3875 5475);
WIRE 16 -1 (-3825 5575)(-3825 5525);
WIRE 16 -1 (-3825 5525)(-3875 5525);
WIRE 16 -1 (-3825 5625)(-3825 5575);
WIRE 16 -1 (-3825 5575)(-3875 5575);
WIRE 16 -1 (-3825 5675)(-3825 5625);
WIRE 16 -1 (-3825 5625)(-3875 5625);
WIRE 16 -1 (-3825 5725)(-3825 5675);
WIRE 16 -1 (-3825 5675)(-3875 5675);
WIRE 16 -1 (-3825 5775)(-3825 5725);
WIRE 16 -1 (-3825 5725)(-3875 5725);
WIRE 16 -1 (-3825 5825)(-3825 5775);
WIRE 16 -1 (-3825 5775)(-3875 5775);
WIRE 16 -1 (-3825 5875)(-3825 5825);
WIRE 16 -1 (-3825 5825)(-3875 5825);
WIRE 16 -1 (-3825 5925)(-3825 5875);
WIRE 16 -1 (-3825 5875)(-3875 5875);
WIRE 16 -1 (-3825 5975)(-3825 5925);
WIRE 16 -1 (-3825 5925)(-3875 5925);
WIRE 16 -1 (-3825 6025)(-3825 5975);
WIRE 16 -1 (-3825 5975)(-3875 5975);
WIRE 16 -1 (-3825 6075)(-3825 6025);
WIRE 16 -1 (-3825 6025)(-3875 6025);
WIRE 16 -1 (-3825 6125)(-3825 6075);
WIRE 16 -1 (-3825 6075)(-3875 6075);
WIRE 16 -1 (-3825 6125)(-3825 6200);
WIRE 16 -1 (-3875 6125)(-3825 6125);
WIRE 16 -1 (-2150 575)(-1450 575);
FORCEPROP 2 LAST SIG_NAME CPU1_VDDBT_RTC_G
J 0
(-2010 585);
DISPLAY 0.489362 (-2010 585);
FORCEPROP 2 LASTPROP $XRERR UNIQUE?
J 0
(-2250 585);
DISPLAY 0.638298 (-2250 585);
PAINT MONO (-2250 585);
DISPLAY INVISIBLE (-2250 585);
WIRE 16 -1 (-1450 575)(-1125 575);
WIRE 16 -1 (-1450 575)(-1450 625);
WIRE 16 -1 (-1125 575)(-1125 625);
DOT 1 (-7425 6350);
DOT 1 (-1450 575);
DOT 1 (-3725 2575);
DOT 1 (-3550 5925);
DOT 1 (-5525 2125);
DOT 1 (-3725 1475);
DOT 1 (-3725 1525);
DOT 1 (-3725 1575);
DOT 1 (-3725 1625);
DOT 1 (-3725 1675);
DOT 1 (-3725 1725);
DOT 1 (-3725 1825);
DOT 1 (-3725 1775);
DOT 1 (-3725 1875);
DOT 1 (-3725 1925);
DOT 1 (-3725 1975);
DOT 1 (-3725 2075);
DOT 1 (-3725 2025);
DOT 1 (-3725 2125);
DOT 1 (-3725 2175);
DOT 1 (-3725 2225);
DOT 1 (-3725 2325);
DOT 1 (-3725 2275);
DOT 1 (-3725 2375);
DOT 1 (-3725 2425);
DOT 1 (-3725 2475);
DOT 1 (-3550 2725);
DOT 1 (-3550 2775);
DOT 1 (-3550 2825);
DOT 1 (-3550 2875);
DOT 1 (-3550 2975);
DOT 1 (-3550 2925);
DOT 1 (-3550 3025);
DOT 1 (-3550 3075);
DOT 1 (-3550 3125);
DOT 1 (-3550 3225);
DOT 1 (-3550 3175);
DOT 1 (-3550 3275);
DOT 1 (-3550 3325);
DOT 1 (-3550 3375);
DOT 1 (-3550 3475);
DOT 1 (-3550 3425);
DOT 1 (-3550 3525);
DOT 1 (-3550 3575);
DOT 1 (-3550 3625);
DOT 1 (-3550 3725);
DOT 1 (-3550 3775);
DOT 1 (-3550 3675);
DOT 1 (-3550 3825);
DOT 1 (-3550 3875);
DOT 1 (-3550 3925);
DOT 1 (-3550 3975);
DOT 1 (-3550 4025);
DOT 1 (-3550 4075);
DOT 1 (-3550 4125);
DOT 1 (-3550 4175);
DOT 1 (-3550 4225);
DOT 1 (-3550 4275);
DOT 1 (-3550 4325);
DOT 1 (-3550 4375);
DOT 1 (-3550 4425);
DOT 1 (-3550 4475);
DOT 1 (-3550 4525);
DOT 1 (-3550 4575);
DOT 1 (-3550 4625);
DOT 1 (-3550 4725);
DOT 1 (-3550 4775);
DOT 1 (-3550 4825);
DOT 1 (-3550 4925);
DOT 1 (-3550 5025);
DOT 1 (-3550 4975);
DOT 1 (-3550 5075);
DOT 1 (-3550 5125);
DOT 1 (-3550 5175);
DOT 1 (-3550 5275);
DOT 1 (-3550 5225);
DOT 1 (-3550 5325);
DOT 1 (-3550 5375);
DOT 1 (-3550 5425);
DOT 1 (-3550 5525);
DOT 1 (-3550 5475);
DOT 1 (-3550 5575);
DOT 1 (-3550 5625);
DOT 1 (-3550 5675);
DOT 1 (-3550 5775);
DOT 1 (-3550 5725);
DOT 1 (-3550 5825);
DOT 1 (-3550 5875);
DOT 1 (-3550 5975);
DOT 1 (-3550 6025);
DOT 1 (-3550 6075);
DOT 1 (-3550 6125);
DOT 1 (-3550 6175);
DOT 1 (-3550 6225);
DOT 1 (-3550 6275);
DOT 1 (-3550 6325);
DOT 1 (-3550 6375);
DOT 1 (-3550 6425);
DOT 1 (-3550 6475);
DOT 1 (-2050 825);
DOT 1 (-2050 1825);
DOT 1 (-2050 1725);
DOT 1 (-2050 1775);
DOT 1 (-2050 1675);
DOT 1 (-2050 1575);
DOT 1 (-2050 1625);
DOT 1 (-2050 1425);
DOT 1 (-2050 1475);
DOT 1 (-2050 1325);
DOT 1 (-2050 1375);
DOT 1 (-2050 1175);
DOT 1 (-2050 1225);
DOT 1 (-2050 1275);
DOT 1 (-2050 1125);
DOT 1 (-2050 1075);
DOT 1 (-2050 1025);
DOT 1 (-2050 925);
DOT 1 (-2050 975);
DOT 1 (-2050 875);
DOT 1 (-2050 2875);
DOT 1 (-2050 2825);
DOT 1 (-2050 2775);
DOT 1 (-2050 2625);
DOT 1 (-2050 2575);
DOT 1 (-2050 2475);
DOT 1 (-2050 2525);
DOT 1 (-2050 2325);
DOT 1 (-2050 2375);
DOT 1 (-2050 2425);
DOT 1 (-2050 2225);
DOT 1 (-2050 2275);
DOT 1 (-2050 2125);
DOT 1 (-2050 2175);
DOT 1 (-2050 2075);
DOT 1 (-2050 1975);
DOT 1 (-2050 2025);
DOT 1 (-2050 1925);
DOT 1 (-2050 1875);
DOT 1 (-2050 3825);
DOT 1 (-2050 3725);
DOT 1 (-2050 3625);
DOT 1 (-2050 3675);
DOT 1 (-2050 3475);
DOT 1 (-2050 3525);
DOT 1 (-2050 3575);
DOT 1 (-2050 3375);
DOT 1 (-2050 3425);
DOT 1 (-2050 3325);
DOT 1 (-2050 3275);
DOT 1 (-2050 3225);
DOT 1 (-2050 3175);
DOT 1 (-2050 2975);
DOT 1 (-2050 2925);
DOT 1 (-2050 4925);
DOT 1 (-2050 4875);
DOT 1 (-2050 4775);
DOT 1 (-2050 4825);
DOT 1 (-2050 4675);
DOT 1 (-2050 4725);
DOT 1 (-2050 4625);
DOT 1 (-2050 4525);
DOT 1 (-2050 4575);
DOT 1 (-2050 4375);
DOT 1 (-2050 4425);
DOT 1 (-2050 4475);
DOT 1 (-2050 4275);
DOT 1 (-2050 4325);
DOT 1 (-2050 4225);
DOT 1 (-2050 4125);
DOT 1 (-2050 4175);
DOT 1 (-2050 4025);
DOT 1 (-2050 4075);
DOT 1 (-2050 3975);
DOT 1 (-2050 3925);
DOT 1 (-2050 5925);
DOT 1 (-2050 5825);
DOT 1 (-2050 5775);
DOT 1 (-2050 5875);
DOT 1 (-2050 5675);
DOT 1 (-2050 5725);
DOT 1 (-2050 5525);
DOT 1 (-2050 5575);
DOT 1 (-2050 5625);
DOT 1 (-2050 5425);
DOT 1 (-2050 5475);
DOT 1 (-2050 5275);
DOT 1 (-2050 5375);
DOT 1 (-2050 5325);
DOT 1 (-2050 5225);
DOT 1 (-2050 5175);
DOT 1 (-2050 5125);
DOT 1 (-2050 5025);
DOT 1 (-2050 5075);
DOT 1 (-2050 4975);
DOT 1 (-2050 6425);
DOT 1 (-2050 6475);
DOT 1 (-2050 6375);
DOT 1 (-2050 6325);
DOT 1 (-2050 6275);
DOT 1 (-2050 6175);
DOT 1 (-2050 6225);
DOT 1 (-2050 6125);
DOT 1 (-2050 6075);
DOT 1 (-2050 6025);
DOT 1 (-2050 5975);
DOT 1 (-6950 775);
DOT 1 (-6950 825);
DOT 1 (-6950 875);
DOT 1 (-6950 925);
DOT 1 (-6950 975);
DOT 1 (-6950 1025);
DOT 1 (-6950 1075);
DOT 1 (-6950 1125);
DOT 1 (-6950 1175);
DOT 1 (-6950 1225);
DOT 1 (-6950 1275);
DOT 1 (-6950 1325);
DOT 1 (-6950 1375);
DOT 1 (-6950 1425);
DOT 1 (-6950 1475);
DOT 1 (-6950 1525);
DOT 1 (-6950 1575);
DOT 1 (-6950 1625);
DOT 1 (-6950 1675);
DOT 1 (-6950 1725);
DOT 1 (-6950 1775);
DOT 1 (-6950 1925);
DOT 1 (-6950 1875);
DOT 1 (-6950 1825);
DOT 1 (-6950 2025);
DOT 1 (-6950 1975);
DOT 1 (-6950 2175);
DOT 1 (-6950 2125);
DOT 1 (-6950 2075);
DOT 1 (-6950 2275);
DOT 1 (-6950 2225);
DOT 1 (-6950 2325);
DOT 1 (-6950 2425);
DOT 1 (-6950 2375);
DOT 1 (-6950 2525);
DOT 1 (-6950 2475);
DOT 1 (-6950 2575);
DOT 1 (-6950 2675);
DOT 1 (-6950 2625);
DOT 1 (-6950 2725);
DOT 1 (-6950 2775);
DOT 1 (-6950 2825);
DOT 1 (-6950 2875);
DOT 1 (-6950 2925);
DOT 1 (-6950 2975);
DOT 1 (-6950 3025);
DOT 1 (-6950 3075);
DOT 1 (-6950 3125);
DOT 1 (-6950 3175);
DOT 1 (-6950 3225);
DOT 1 (-6950 3275);
DOT 1 (-6950 3325);
DOT 1 (-6950 3375);
DOT 1 (-6950 3425);
DOT 1 (-6950 3475);
DOT 1 (-6950 3525);
DOT 1 (-6950 3575);
DOT 1 (-6950 3625);
DOT 1 (-6950 3675);
DOT 1 (-6950 3725);
DOT 1 (-6950 3775);
DOT 1 (-6950 3825);
DOT 1 (-6950 3975);
DOT 1 (-6950 3925);
DOT 1 (-6950 3875);
DOT 1 (-6950 4075);
DOT 1 (-6950 4025);
DOT 1 (-6950 4225);
DOT 1 (-6950 4175);
DOT 1 (-6950 4125);
DOT 1 (-6950 4325);
DOT 1 (-6950 4275);
DOT 1 (-6950 4375);
DOT 1 (-6950 4475);
DOT 1 (-6950 4425);
DOT 1 (-6950 4575);
DOT 1 (-6950 4525);
DOT 1 (-6950 4625);
DOT 1 (-6950 4725);
DOT 1 (-6950 4675);
DOT 1 (-6950 4825);
DOT 1 (-6950 4775);
DOT 1 (-6950 4875);
DOT 1 (-6950 4975);
DOT 1 (-6950 4925);
DOT 1 (-6950 5025);
DOT 1 (-6950 5075);
DOT 1 (-6950 5125);
DOT 1 (-6950 5175);
DOT 1 (-6950 5225);
DOT 1 (-6950 5275);
DOT 1 (-6950 5325);
DOT 1 (-6950 5375);
DOT 1 (-6950 5425);
DOT 1 (-6950 5475);
DOT 1 (-6950 5525);
DOT 1 (-6950 5575);
DOT 1 (-6950 5625);
DOT 1 (-6950 5725);
DOT 1 (-6950 5775);
DOT 1 (-6950 5825);
DOT 1 (-6950 5875);
DOT 1 (-6950 6025);
DOT 1 (-6950 5975);
DOT 1 (-6950 6125);
DOT 1 (-6950 6075);
DOT 1 (-5525 375);
DOT 1 (-5525 325);
DOT 1 (-5525 425);
DOT 1 (-5525 475);
DOT 1 (-5525 525);
DOT 1 (-5525 575);
DOT 1 (-5525 625);
DOT 1 (-5525 725);
DOT 1 (-5525 775);
DOT 1 (-5525 675);
DOT 1 (-5525 825);
DOT 1 (-5525 875);
DOT 1 (-5525 925);
DOT 1 (-5525 975);
DOT 1 (-5525 1025);
DOT 1 (-5525 1075);
DOT 1 (-5525 1125);
DOT 1 (-5525 1175);
DOT 1 (-5525 1225);
DOT 1 (-5525 1275);
DOT 1 (-5525 1325);
DOT 1 (-5525 1375);
DOT 1 (-5525 1425);
DOT 1 (-5525 1475);
DOT 1 (-5525 1525);
DOT 1 (-5525 1575);
DOT 1 (-5525 1625);
DOT 1 (-5525 1675);
DOT 1 (-5525 1725);
DOT 1 (-5525 1775);
DOT 1 (-5525 1825);
DOT 1 (-5525 1875);
DOT 1 (-5525 1925);
DOT 1 (-5525 1975);
DOT 1 (-5525 2025);
DOT 1 (-5525 2075);
DOT 1 (-5525 2175);
DOT 1 (-5525 2225);
DOT 1 (-5525 2275);
DOT 1 (-5525 2325);
DOT 1 (-5525 2375);
DOT 1 (-5525 2425);
DOT 1 (-5525 2475);
DOT 1 (-5525 2525);
DOT 1 (-5525 2575);
DOT 1 (-5525 2625);
DOT 1 (-5525 2675);
DOT 1 (-5525 2775);
DOT 1 (-5525 2825);
DOT 1 (-5525 2875);
DOT 1 (-5525 2925);
DOT 1 (-5525 2975);
DOT 1 (-5525 3025);
DOT 1 (-5525 3075);
DOT 1 (-5525 3225);
DOT 1 (-5525 3275);
DOT 1 (-5525 3325);
DOT 1 (-5525 3375);
DOT 1 (-5525 3425);
DOT 1 (-5525 3475);
DOT 1 (-5525 3525);
DOT 1 (-5525 3575);
DOT 1 (-5525 3625);
DOT 1 (-5525 3675);
DOT 1 (-5525 3725);
DOT 1 (-5525 3775);
DOT 1 (-5525 3825);
DOT 1 (-5525 3875);
DOT 1 (-5525 3925);
DOT 1 (-5525 3975);
DOT 1 (-5525 4025);
DOT 1 (-5525 4075);
DOT 1 (-5525 4125);
DOT 1 (-5525 4175);
DOT 1 (-5525 4225);
DOT 1 (-5525 4275);
DOT 1 (-5525 4325);
DOT 1 (-5525 4375);
DOT 1 (-5525 4425);
DOT 1 (-5525 4475);
DOT 1 (-5525 4525);
DOT 1 (-5525 4575);
DOT 1 (-5525 4625);
DOT 1 (-5525 4675);
DOT 1 (-5525 4725);
DOT 1 (-5525 4775);
DOT 1 (-5525 4825);
DOT 1 (-5525 4875);
DOT 1 (-5525 4925);
DOT 1 (-5525 4975);
DOT 1 (-5525 5025);
DOT 1 (-5525 5075);
DOT 1 (-5525 5125);
DOT 1 (-5525 5175);
DOT 1 (-5525 5225);
DOT 1 (-5525 5275);
DOT 1 (-5525 5325);
DOT 1 (-5525 5375);
DOT 1 (-5525 5425);
DOT 1 (-5525 5475);
DOT 1 (-5525 5525);
DOT 1 (-5525 5575);
DOT 1 (-5525 5625);
DOT 1 (-5525 5675);
DOT 1 (-5525 5725);
DOT 1 (-5525 5775);
DOT 1 (-5525 5825);
DOT 1 (-5525 5875);
DOT 1 (-5525 5925);
DOT 1 (-5525 5975);
DOT 1 (-5525 6025);
DOT 1 (-5525 6075);
DOT 1 (-5525 6125);
DOT 1 (-5525 6175);
DOT 1 (-5525 6225);
DOT 1 (-5525 6275);
DOT 1 (-5525 6325);
DOT 1 (-5525 6375);
DOT 1 (-5525 6425);
DOT 1 (-7425 2300);
DOT 1 (-8875 650);
DOT 1 (-8875 700);
DOT 1 (-8875 750);
DOT 1 (-8875 800);
DOT 1 (-8875 850);
DOT 1 (-8875 900);
DOT 1 (-8875 950);
DOT 1 (-8875 1000);
DOT 1 (-8875 1050);
DOT 1 (-8875 1100);
DOT 1 (-8875 1150);
DOT 1 (-8875 1200);
DOT 1 (-8875 1250);
DOT 1 (-8875 1300);
DOT 1 (-8875 1350);
DOT 1 (-8875 1400);
DOT 1 (-8875 1450);
DOT 1 (-8875 1500);
DOT 1 (-8875 1550);
DOT 1 (-8875 1600);
DOT 1 (-8875 1650);
DOT 1 (-8875 1700);
DOT 1 (-8875 1750);
DOT 1 (-8875 1800);
DOT 1 (-8875 1850);
DOT 1 (-8875 1900);
DOT 1 (-8875 1950);
DOT 1 (-8875 2000);
DOT 1 (-8875 2050);
DOT 1 (-8875 2100);
DOT 1 (-8875 2150);
DOT 1 (-8875 2200);
DOT 1 (-8875 2250);
DOT 1 (-8875 2300);
DOT 1 (-8875 2350);
DOT 1 (-8875 2400);
DOT 1 (-8875 2450);
DOT 1 (-8875 2500);
DOT 1 (-8875 2550);
DOT 1 (-8875 2600);
DOT 1 (-8875 2650);
DOT 1 (-8875 2700);
DOT 1 (-8875 2750);
DOT 1 (-8875 2800);
DOT 1 (-8875 2850);
DOT 1 (-8875 2900);
DOT 1 (-8875 2950);
DOT 1 (-7425 650);
DOT 1 (-7425 600);
DOT 1 (-7425 750);
DOT 1 (-7425 700);
DOT 1 (-7425 800);
DOT 1 (-7425 850);
DOT 1 (-7425 900);
DOT 1 (-7425 1000);
DOT 1 (-7425 950);
DOT 1 (-7425 1050);
DOT 1 (-7425 1100);
DOT 1 (-7425 1150);
DOT 1 (-7425 1250);
DOT 1 (-7425 1200);
DOT 1 (-7425 1300);
DOT 1 (-7425 1350);
DOT 1 (-7425 1400);
DOT 1 (-7425 1500);
DOT 1 (-7425 1450);
DOT 1 (-7425 1550);
DOT 1 (-7425 1600);
DOT 1 (-7425 1650);
DOT 1 (-7425 1700);
DOT 1 (-7425 1750);
DOT 1 (-7425 1800);
DOT 1 (-7425 1850);
DOT 1 (-7425 1950);
DOT 1 (-7425 2000);
DOT 1 (-7425 2050);
DOT 1 (-7425 2150);
DOT 1 (-7425 2100);
DOT 1 (-7425 2250);
DOT 1 (-7425 2200);
DOT 1 (-7425 2400);
DOT 1 (-7425 2350);
DOT 1 (-7425 2450);
DOT 1 (-7425 2500);
DOT 1 (-7425 2550);
DOT 1 (-7425 2650);
DOT 1 (-7425 2600);
DOT 1 (-7425 2700);
DOT 1 (-7425 2750);
DOT 1 (-7425 2800);
DOT 1 (-7425 2850);
DOT 1 (-7425 2900);
DOT 1 (-7425 2950);
DOT 1 (-8875 3000);
DOT 1 (-8875 3050);
DOT 1 (-8875 3100);
DOT 1 (-8875 3150);
DOT 1 (-8875 3200);
DOT 1 (-8875 3250);
DOT 1 (-8875 3300);
DOT 1 (-8875 3350);
DOT 1 (-8875 3400);
DOT 1 (-8875 3450);
DOT 1 (-8875 3500);
DOT 1 (-8875 3550);
DOT 1 (-8875 3600);
DOT 1 (-8875 3650);
DOT 1 (-8875 3700);
DOT 1 (-8875 3750);
DOT 1 (-8875 3800);
DOT 1 (-8875 3850);
DOT 1 (-8875 3900);
DOT 1 (-8875 3950);
DOT 1 (-8875 4000);
DOT 1 (-8875 4050);
DOT 1 (-8875 4100);
DOT 1 (-8875 4150);
DOT 1 (-8875 4200);
DOT 1 (-8875 4250);
DOT 1 (-8875 4300);
DOT 1 (-8875 4350);
DOT 1 (-8875 4400);
DOT 1 (-8875 4450);
DOT 1 (-8875 4500);
DOT 1 (-8875 4550);
DOT 1 (-8875 4600);
DOT 1 (-8875 4650);
DOT 1 (-8875 4700);
DOT 1 (-8875 4750);
DOT 1 (-8875 4800);
DOT 1 (-8875 4850);
DOT 1 (-8875 4900);
DOT 1 (-8875 4950);
DOT 1 (-8875 5000);
DOT 1 (-8875 5050);
DOT 1 (-8875 5100);
DOT 1 (-8875 5150);
DOT 1 (-8875 5200);
DOT 1 (-8875 5250);
DOT 1 (-8875 5300);
DOT 1 (-8875 5350);
DOT 1 (-8875 5400);
DOT 1 (-8875 5450);
DOT 1 (-8875 5500);
DOT 1 (-8875 5550);
DOT 1 (-8875 5600);
DOT 1 (-8875 5650);
DOT 1 (-8875 5700);
DOT 1 (-8875 5750);
DOT 1 (-8875 5800);
DOT 1 (-8875 5850);
DOT 1 (-8875 5900);
DOT 1 (-8875 5950);
DOT 1 (-8875 6000);
DOT 1 (-8875 6050);
DOT 1 (-8875 6100);
DOT 1 (-8875 6150);
DOT 1 (-8875 6200);
DOT 1 (-8875 6250);
DOT 1 (-8875 6300);
DOT 1 (-8875 6350);
DOT 1 (-7425 3000);
DOT 1 (-7425 3100);
DOT 1 (-7425 3150);
DOT 1 (-7425 3200);
DOT 1 (-7425 3300);
DOT 1 (-7425 3250);
DOT 1 (-7425 3350);
DOT 1 (-7425 3400);
DOT 1 (-7425 3450);
DOT 1 (-7425 3550);
DOT 1 (-7425 3500);
DOT 1 (-7425 3600);
DOT 1 (-7425 3650);
DOT 1 (-7425 3700);
DOT 1 (-7425 3850);
DOT 1 (-7425 3800);
DOT 1 (-7425 3750);
DOT 1 (-7425 3950);
DOT 1 (-7425 3900);
DOT 1 (-7425 4000);
DOT 1 (-7425 4050);
DOT 1 (-7425 4100);
DOT 1 (-7425 4200);
DOT 1 (-7425 4150);
DOT 1 (-7425 4250);
DOT 1 (-7425 4300);
DOT 1 (-7425 4450);
DOT 1 (-7425 4500);
DOT 1 (-7425 4550);
DOT 1 (-7425 4600);
DOT 1 (-7425 4700);
DOT 1 (-7425 4650);
DOT 1 (-7425 4750);
DOT 1 (-7425 4800);
DOT 1 (-7425 4850);
DOT 1 (-7425 4900);
DOT 1 (-7425 4950);
DOT 1 (-7425 5000);
DOT 1 (-7425 5100);
DOT 1 (-7425 5050);
DOT 1 (-7425 5150);
DOT 1 (-7425 5200);
DOT 1 (-7425 5250);
DOT 1 (-7425 5350);
DOT 1 (-7425 5300);
DOT 1 (-7425 5450);
DOT 1 (-7425 5400);
DOT 1 (-7425 5500);
DOT 1 (-7425 5600);
DOT 1 (-7425 5550);
DOT 1 (-7425 5650);
DOT 1 (-7425 5700);
DOT 1 (-7425 5750);
DOT 1 (-7425 5850);
DOT 1 (-7425 5800);
DOT 1 (-7425 5900);
DOT 1 (-7425 5950);
DOT 1 (-7425 6000);
DOT 1 (-7425 6050);
DOT 1 (-7425 6100);
DOT 1 (-7425 6150);
DOT 1 (-7425 6250);
DOT 1 (-7425 6200);
DOT 1 (-7425 6300);
DOT 1 (-3550 4675);
DOT 1 (-2050 3875);
DOT 1 (-2050 3775);
DOT 1 (-2050 2675);
DOT 1 (-2050 2725);
DOT 1 (-6950 5925);
DOT 1 (-7425 4400);
DOT 1 (-7425 4350);
DOT 1 (-7425 3050);
DOT 1 (-3550 4875);
DOT 1 (-3825 6125);
DOT 1 (-3825 6075);
DOT 1 (-3825 6025);
DOT 1 (-3825 5975);
DOT 1 (-3825 5925);
DOT 1 (-3825 5875);
DOT 1 (-3825 5825);
DOT 1 (-3825 5775);
DOT 1 (-3825 5725);
DOT 1 (-3825 5675);
DOT 1 (-3825 5625);
DOT 1 (-3825 5575);
DOT 1 (-3825 5525);
DOT 1 (-3825 5475);
DOT 1 (-3825 5425);
DOT 1 (-3825 5375);
DOT 1 (-3825 5325);
DOT 1 (-3825 5275);
DOT 1 (-3825 5225);
DOT 1 (-3825 5175);
DOT 1 (-3825 5125);
DOT 1 (-3825 5075);
DOT 1 (-3825 5025);
DOT 1 (-3825 4975);
DOT 1 (-3825 4925);
DOT 1 (-3825 4875);
DOT 1 (-3825 4825);
DOT 1 (-3825 4775);
DOT 1 (-3825 4725);
DOT 1 (-3825 4675);
DOT 1 (-3825 4625);
DOT 1 (-3825 4575);
DOT 1 (-3825 4525);
DOT 1 (-3825 4475);
DOT 1 (-3825 4425);
DOT 1 (-3825 4375);
DOT 1 (-3825 4325);
DOT 1 (-5125 6125);
DOT 1 (-5125 6075);
DOT 1 (-5125 6025);
DOT 1 (-5125 5975);
DOT 1 (-5125 5925);
DOT 1 (-5125 5875);
DOT 1 (-5125 5825);
DOT 1 (-5125 5775);
DOT 1 (-5125 5725);
DOT 1 (-5125 5575);
DOT 1 (-5125 5675);
DOT 1 (-5125 5625);
DOT 1 (-5125 5525);
DOT 1 (-5125 5475);
DOT 1 (-5125 5425);
DOT 1 (-5125 5325);
DOT 1 (-5125 5375);
DOT 1 (-5125 5275);
DOT 1 (-5125 5225);
DOT 1 (-5125 5175);
DOT 1 (-5125 5075);
DOT 1 (-5125 5125);
DOT 1 (-5125 5025);
DOT 1 (-5125 4975);
DOT 1 (-5125 4925);
DOT 1 (-5125 4825);
DOT 1 (-5125 4875);
DOT 1 (-5125 4775);
DOT 1 (-5125 4725);
DOT 1 (-5125 4675);
DOT 1 (-5125 4625);
DOT 1 (-5125 4575);
DOT 1 (-5125 4525);
DOT 1 (-5125 4475);
DOT 1 (-5125 4425);
DOT 1 (-5125 4375);
DOT 1 (-5125 4325);
DOT 1 (-3825 4275);
DOT 1 (-5125 4275);
DOT 1 (-3825 4225);
DOT 1 (-3825 4175);
DOT 1 (-3825 4125);
DOT 1 (-3825 4075);
DOT 1 (-3825 4025);
DOT 1 (-3825 3975);
DOT 1 (-3825 3925);
DOT 1 (-3825 3875);
DOT 1 (-3825 3825);
DOT 1 (-3825 3775);
DOT 1 (-3825 3725);
DOT 1 (-3825 3675);
DOT 1 (-3825 3625);
DOT 1 (-5125 4225);
DOT 1 (-5125 4175);
DOT 1 (-5125 4125);
DOT 1 (-5125 4025);
DOT 1 (-5125 4075);
DOT 1 (-5125 3975);
DOT 1 (-5125 3925);
DOT 1 (-5125 3875);
DOT 1 (-5125 3825);
DOT 1 (-5125 3775);
DOT 1 (-5125 3725);
DOT 1 (-5125 3675);
DOT 1 (-5125 3625);
DOT 1 (-5125 3575);
DOT 1 (-5125 3525);
DOT 1 (-5125 3475);
DOT 1 (-5125 3425);
DOT 1 (-5125 3375);
DOT 1 (-5125 3275);
DOT 1 (-5125 3325);
DOT 1 (-5125 3225);
DOT 1 (-5525 2725);
DOT 1 (-5525 3125);
DOT 1 (-5525 3175);
DOT 1 (-7425 1900);
DOT 1 (-6950 5675);
DOT 1 (-2050 3125);
DOT 1 (-2050 3075);
DOT 1 (-2050 3025);
DOT 1 (-2050 1525);
DOT 1 (-3725 875);
QUIT
